FILE_TYPE = MACRO_DRAWING;
SET COLOR_WIRE YELLOW;
SET COLOR_PROP MONO;
SET COLOR_DOT WHITE;
SET COLOR_ARC YELLOW;
SET COLOR_BODY GREEN;
SET COLOR_NOTE MONO;
SET PROP_DISPLAY VALUE;
SET PAGE_NUMBER P90;
FORCEADD OFFPAGE..2
(475 3400);
FORCEPROP 2 LAST $XR0 21 
J 0
(664 3400);
DISPLAY 0.638298 (664 3400);
PAINT MONO (664 3400);
FORCEPROP 1 LAST OFFPAGE TRUE
J 0
(800 3275);
PAINT GREEN (800 3275);
DISPLAY INVISIBLE (800 3275);
FORCEPROP 2 LAST PATH I1
J 0
(675 3450);
DISPLAY 1.021277 (675 3450);
PAINT ORANGE (675 3450);
DISPLAY INVISIBLE (675 3450);
FORCEPROP 2 LAST CDS_LIB mstr_standard
J 0
(475 3400);
PAINT ORANGE (475 3400);
DISPLAY INVISIBLE (475 3400);
FORCEPROP 1 LAST COMMENT_BODY TRUE
J 0
(430 3305);
DISPLAY 1.170213 (430 3305);
PAINT GREEN (430 3305);
DISPLAY INVISIBLE (430 3305);
FORCEADD OFFPAGE..2
(550 1050);
FORCEPROP 2 LAST $XR0 55 
J 0
(739 1050);
DISPLAY 0.638298 (739 1050);
PAINT MONO (739 1050);
FORCEPROP 2 LAST PATH I10
J 0
(750 1100);
DISPLAY 1.021277 (750 1100);
PAINT ORANGE (750 1100);
DISPLAY INVISIBLE (750 1100);
FORCEPROP 2 LAST CDS_LIB mstr_standard
J 0
(550 1050);
PAINT ORANGE (550 1050);
DISPLAY INVISIBLE (550 1050);
FORCEPROP 1 LAST OFFPAGE TRUE
J 0
(875 925);
PAINT GREEN (875 925);
DISPLAY INVISIBLE (875 925);
FORCEPROP 1 LAST COMMENT_BODY TRUE
J 0
(505 955);
DISPLAY 1.170213 (505 955);
PAINT GREEN (505 955);
DISPLAY INVISIBLE (505 955);
FORCEADD RES..1
(-425 850);
FORCEPROP 1 LAST PART_NUMBER G21796-294
J 0
(-300 850);
DISPLAY 0.617021 (-300 850);
PAINT BLUE (-300 850);
FORCEPROP 1 LAST WATTAGE 1/16W
J 2
(-375 800);
DISPLAY 0.617021 (-375 800);
PAINT SKYBLUE (-375 800);
FORCEPROP 1 LASTPIN (-325 850) $PN 2
J 0
(-363 862);
DISPLAY 0.617021 (-363 862);
PAINT MONO (-363 862);
FORCEPROP 1 LAST TOLERANCE 1.0%
J 0
(-600 800);
DISPLAY 0.617021 (-600 800);
PAINT SKYBLUE (-600 800);
FORCEPROP 1 LAST VALUE 240
J 2
(-625 800);
DISPLAY 0.617021 (-625 800);
PAINT SKYBLUE (-625 800);
FORCEPROP 1 LAST MATERIAL CHIP
J 0
(-225 800);
DISPLAY 0.617021 (-225 800);
PAINT SKYBLUE (-225 800);
FORCEPROP 1 LAST PACK_TYPE 0402
J 0
(-350 800);
DISPLAY 0.617021 (-350 800);
PAINT SKYBLUE (-350 800);
FORCEPROP 1 LASTPIN (-525 850) $PN 1
J 0
(-513 862);
DISPLAY 0.617021 (-513 862);
PAINT MONO (-513 862);
FORCEPROP 1 LAST LOCATION R7P14
J 0
(-650 850);
DISPLAY 0.617021 (-650 850);
PAINT AQUA (-650 850);
FORCEPROP 2 LAST SEC 1
J 0
(-475 1050);
DISPLAY 0.680851 (-475 1050);
PAINT MONO (-475 1050);
DISPLAY INVISIBLE (-475 1050);
FORCEPROP 2 LAST SEC_TYPE 0402
J 0
(-475 1050);
DISPLAY 1.021277 (-475 1050);
PAINT ORANGE (-475 1050);
DISPLAY INVISIBLE (-475 1050);
FORCEPROP 2 LAST CDS_LIB mstr_discrete
J 0
(-425 850);
PAINT ORANGE (-425 850);
DISPLAY INVISIBLE (-425 850);
FORCEPROP 2 LAST BOM_COST PROC
J 0
(-425 850);
PAINT MONO (-425 850);
DISPLAY INVISIBLE (-425 850);
FORCEPROP 2 LAST ROOM PROC_SIDEBAND
J 0
(-325 950);
PAINT MONO (-325 950);
DISPLAY INVISIBLE (-325 950);
FORCEPROP 1 LAST PATH I100
J 0
(-475 1000);
DISPLAY 0.978723 (-475 1000);
PAINT WHITE (-475 1000);
DISPLAY INVISIBLE (-475 1000);
FORCEPROP 2 LAST CDS_LOCATION R7P14
J 0
(-700 875);
DISPLAY 0.617021 (-700 875);
PAINT AQUA (-700 875);
DISPLAY INVISIBLE (-700 875);
FORCEADD RES..1
(-575 3400);
FORCEPROP 1 LAST MATERIAL EMPTY
J 0
(-375 3350);
DISPLAY 0.617021 (-375 3350);
PAINT RED (-375 3350);
FORCEPROP 1 LAST PACK_TYPE 0402
J 0
(-500 3350);
DISPLAY 0.617021 (-500 3350);
PAINT SKYBLUE (-500 3350);
FORCEPROP 1 LASTPIN (-475 3400) $PN 2
J 0
(-513 3412);
DISPLAY 0.617021 (-513 3412);
PAINT ORANGE (-513 3412);
FORCEPROP 1 LASTPIN (-675 3400) $PN 1
J 0
(-663 3412);
DISPLAY 0.617021 (-663 3412);
PAINT ORANGE (-663 3412);
FORCEPROP 1 LAST TOLERANCE 1.0%
J 0
(-750 3350);
DISPLAY 0.617021 (-750 3350);
PAINT SKYBLUE (-750 3350);
FORCEPROP 1 LAST VALUE 240
J 2
(-775 3350);
DISPLAY 0.617021 (-775 3350);
PAINT SKYBLUE (-775 3350);
FORCEPROP 1 LAST LOCATION R6D6
J 0
(-800 3400);
DISPLAY 0.617021 (-800 3400);
PAINT AQUA (-800 3400);
FORCEPROP 1 LAST WATTAGE 1/16W
J 2
(-525 3350);
DISPLAY 0.617021 (-525 3350);
PAINT SKYBLUE (-525 3350);
FORCEPROP 1 LAST PART_NUMBER G21796-294
J 0
(-425 3400);
DISPLAY 0.617021 (-425 3400);
PAINT BLUE (-425 3400);
FORCEPROP 0 LAST ROOM PROC_SIDEBAND
J 0
(-200 3550);
DISPLAY 1.021277 (-200 3550);
PAINT ORANGE (-200 3550);
DISPLAY INVISIBLE (-200 3550);
FORCEPROP 2 LAST SEC 1
J 0
(-625 3600);
DISPLAY 0.680851 (-625 3600);
PAINT MONO (-625 3600);
DISPLAY INVISIBLE (-625 3600);
FORCEPROP 2 LAST SEC_TYPE 0402
J 0
(-625 3600);
DISPLAY 1.021277 (-625 3600);
PAINT ORANGE (-625 3600);
DISPLAY INVISIBLE (-625 3600);
FORCEPROP 2 LAST CDS_LIB mstr_discrete
J 0
(-575 3400);
PAINT ORANGE (-575 3400);
DISPLAY INVISIBLE (-575 3400);
FORCEPROP 2 LAST BOM_COST PROC
J 0
(-575 3400);
PAINT MONO (-575 3400);
DISPLAY INVISIBLE (-575 3400);
FORCEPROP 1 LAST PATH I101
J 0
(-625 3550);
DISPLAY 0.978723 (-625 3550);
PAINT WHITE (-625 3550);
DISPLAY INVISIBLE (-625 3550);
FORCEPROP 2 LAST CDS_LOCATION R6D6
J 0
(-850 3425);
DISPLAY 0.617021 (-850 3425);
PAINT AQUA (-850 3425);
DISPLAY INVISIBLE (-850 3425);
FORCEADD RES..1
(-425 1275);
FORCEPROP 1 LAST VALUE 240
J 2
(-625 1225);
DISPLAY 0.617021 (-625 1225);
PAINT SKYBLUE (-625 1225);
FORCEPROP 1 LASTPIN (-325 1275) $PN 2
J 0
(-363 1287);
DISPLAY 0.617021 (-363 1287);
PAINT ORANGE (-363 1287);
FORCEPROP 1 LAST TOLERANCE 1.0%
J 0
(-600 1225);
DISPLAY 0.617021 (-600 1225);
PAINT SKYBLUE (-600 1225);
FORCEPROP 1 LASTPIN (-525 1275) $PN 1
J 0
(-513 1287);
DISPLAY 0.617021 (-513 1287);
PAINT ORANGE (-513 1287);
FORCEPROP 1 LAST MATERIAL EMPTY
J 0
(-225 1225);
DISPLAY 0.617021 (-225 1225);
PAINT RED (-225 1225);
FORCEPROP 1 LAST PACK_TYPE 0402
J 0
(-350 1225);
DISPLAY 0.617021 (-350 1225);
PAINT SKYBLUE (-350 1225);
FORCEPROP 1 LAST PART_NUMBER G21796-294
J 0
(-300 1275);
DISPLAY 0.617021 (-300 1275);
PAINT BLUE (-300 1275);
FORCEPROP 1 LAST LOCATION R3D12
J 0
(-650 1275);
DISPLAY 0.617021 (-650 1275);
PAINT AQUA (-650 1275);
FORCEPROP 1 LAST WATTAGE 1/16W
J 2
(-375 1225);
DISPLAY 0.617021 (-375 1225);
PAINT SKYBLUE (-375 1225);
FORCEPROP 0 LAST ROOM PROC_SIDEBAND
J 0
(-50 1425);
DISPLAY 1.021277 (-50 1425);
PAINT ORANGE (-50 1425);
DISPLAY INVISIBLE (-50 1425);
FORCEPROP 2 LAST SEC_TYPE 0402
J 0
(-475 1475);
DISPLAY 1.021277 (-475 1475);
PAINT ORANGE (-475 1475);
DISPLAY INVISIBLE (-475 1475);
FORCEPROP 2 LAST SEC 1
J 0
(-475 1475);
DISPLAY 0.680851 (-475 1475);
PAINT MONO (-475 1475);
DISPLAY INVISIBLE (-475 1475);
FORCEPROP 2 LAST BOM_COST PROC
J 0
(-425 1275);
PAINT MONO (-425 1275);
DISPLAY INVISIBLE (-425 1275);
FORCEPROP 2 LAST CDS_LIB mstr_discrete
J 0
(-425 1275);
PAINT ORANGE (-425 1275);
DISPLAY INVISIBLE (-425 1275);
FORCEPROP 1 LAST PATH I102
J 0
(-475 1425);
DISPLAY 0.978723 (-475 1425);
PAINT WHITE (-475 1425);
DISPLAY INVISIBLE (-475 1425);
FORCEPROP 2 LAST CDS_LOCATION R3D12
J 0
(-725 1300);
DISPLAY 0.617021 (-725 1300);
PAINT AQUA (-725 1300);
DISPLAY INVISIBLE (-725 1300);
FORCEADD OFFPAGE..2
(-1300 3800);
FORCEPROP 2 LAST $XR0 21 
J 0
(-1111 3800);
DISPLAY 0.638298 (-1111 3800);
PAINT MONO (-1111 3800);
FORCEPROP 1 LAST OFFPAGE TRUE
J 0
(-975 3675);
PAINT GREEN (-975 3675);
DISPLAY INVISIBLE (-975 3675);
FORCEPROP 2 LAST PATH I14
J 0
(-1100 3850);
DISPLAY 1.021277 (-1100 3850);
PAINT ORANGE (-1100 3850);
DISPLAY INVISIBLE (-1100 3850);
FORCEPROP 2 LAST CDS_LIB mstr_standard
J 0
(-1300 3800);
PAINT ORANGE (-1300 3800);
DISPLAY INVISIBLE (-1300 3800);
FORCEPROP 1 LAST COMMENT_BODY TRUE
J 0
(-1345 3705);
DISPLAY 1.170213 (-1345 3705);
PAINT GREEN (-1345 3705);
DISPLAY INVISIBLE (-1345 3705);
FORCEADD OFFPAGE..2
(-1350 1875);
FORCEPROP 2 LAST $XR0 55 
J 0
(-1161 1875);
DISPLAY 0.638298 (-1161 1875);
PAINT MONO (-1161 1875);
FORCEPROP 2 LAST PATH I16
J 0
(-1150 1925);
DISPLAY 1.021277 (-1150 1925);
PAINT ORANGE (-1150 1925);
DISPLAY INVISIBLE (-1150 1925);
FORCEPROP 1 LAST OFFPAGE TRUE
J 0
(-1025 1750);
PAINT GREEN (-1025 1750);
DISPLAY INVISIBLE (-1025 1750);
FORCEPROP 2 LAST CDS_LIB mstr_standard
J 0
(-1350 1875);
PAINT ORANGE (-1350 1875);
DISPLAY INVISIBLE (-1350 1875);
FORCEPROP 1 LAST COMMENT_BODY TRUE
J 0
(-1395 1780);
DISPLAY 1.170213 (-1395 1780);
PAINT GREEN (-1395 1780);
DISPLAY INVISIBLE (-1395 1780);
FORCEADD RES..1
(-2450 1875);
FORCEPROP 1 LAST LOCATION R3D22
J 0
(-2675 1875);
DISPLAY 0.617021 (-2675 1875);
PAINT AQUA (-2675 1875);
FORCEPROP 1 LAST VALUE 240
J 2
(-2650 1825);
DISPLAY 0.617021 (-2650 1825);
PAINT SKYBLUE (-2650 1825);
FORCEPROP 1 LASTPIN (-2350 1875) $PN 2
J 0
(-2388 1887);
DISPLAY 0.617021 (-2388 1887);
PAINT MONO (-2388 1887);
FORCEPROP 1 LASTPIN (-2550 1875) $PN 1
J 0
(-2538 1887);
DISPLAY 0.617021 (-2538 1887);
PAINT MONO (-2538 1887);
FORCEPROP 1 LAST PACK_TYPE 0402
J 0
(-2375 1825);
DISPLAY 0.617021 (-2375 1825);
PAINT SKYBLUE (-2375 1825);
FORCEPROP 1 LAST MATERIAL EMPTY
J 0
(-2250 1825);
DISPLAY 0.617021 (-2250 1825);
PAINT RED (-2250 1825);
FORCEPROP 1 LAST PART_NUMBER G21796-294
J 0
(-2325 1875);
DISPLAY 0.617021 (-2325 1875);
PAINT BLUE (-2325 1875);
FORCEPROP 1 LAST WATTAGE 1/16W
J 2
(-2400 1825);
DISPLAY 0.617021 (-2400 1825);
PAINT SKYBLUE (-2400 1825);
FORCEPROP 1 LAST TOLERANCE 1.0%
J 0
(-2625 1825);
DISPLAY 0.617021 (-2625 1825);
PAINT SKYBLUE (-2625 1825);
FORCEPROP 2 LAST SEC_TYPE 0402
J 0
(-2500 2075);
PAINT MONO (-2500 2075);
DISPLAY INVISIBLE (-2500 2075);
FORCEPROP 2 LAST SEC 1
J 0
(-2500 2075);
DISPLAY 0.936170 (-2500 2075);
PAINT MONO (-2500 2075);
DISPLAY INVISIBLE (-2500 2075);
FORCEPROP 1 LAST PATH I17
J 0
(-2500 2025);
DISPLAY 0.978723 (-2500 2025);
PAINT WHITE (-2500 2025);
DISPLAY INVISIBLE (-2500 2025);
FORCEPROP 2 LAST ROOM PROC_SIDEBAND
J 0
(-2100 1975);
PAINT MONO (-2100 1975);
DISPLAY INVISIBLE (-2100 1975);
FORCEPROP 2 LAST CDS_LIB mstr_discrete
J 0
(-2450 1875);
PAINT ORANGE (-2450 1875);
DISPLAY INVISIBLE (-2450 1875);
FORCEPROP 2 LAST BOM_COST PROC
J 2
(-2450 1875);
PAINT MONO (-2450 1875);
DISPLAY INVISIBLE (-2450 1875);
FORCEPROP 2 LAST CDS_LOCATION R3D22
J 0
(-2725 1900);
DISPLAY 0.617021 (-2725 1900);
PAINT AQUA (-2725 1900);
DISPLAY INVISIBLE (-2725 1900);
FORCEADD GND..1
(-725 525);
FORCEPROP 3 LASTPIN (-725 575) SIG_NAME GND\g
J 0
(-715 585);
DISPLAY 0.659574 (-715 585);
PAINT MONO (-715 585);
DISPLAY INVISIBLE (-715 585);
FORCEPROP 1 LAST HDL_POWER GND
J 0
(-725 675);
DISPLAY 0.872340 (-725 675);
PAINT GREEN (-725 675);
DISPLAY INVISIBLE (-725 675);
FORCEPROP 2 LAST CDS_LIB mstr_symbols
J 0
(-725 525);
PAINT ORANGE (-725 525);
DISPLAY INVISIBLE (-725 525);
FORCEPROP 1 LAST VOLTAGE 0
J 0
(-725 525);
PAINT SKYBLUE (-725 525);
DISPLAY INVISIBLE (-725 525);
FORCEPROP 1 LAST PATH I18
J 0
(-650 525);
DISPLAY 0.872340 (-650 525);
PAINT AQUA (-650 525);
DISPLAY INVISIBLE (-650 525);
FORCEPROP 1 LAST BODY_TYPE PLUMBING
J 0
(-770 482);
DISPLAY 0.340426 (-770 482);
PAINT GREEN (-770 482);
DISPLAY INVISIBLE (-770 482);
FORCEPROP 1 LAST SIZE 1B
J 0
(-650 475);
DISPLAY 0.872340 (-650 475);
PAINT GREEN (-650 475);
DISPLAY INVISIBLE (-650 475);
FORCEADD OFFPAGE..2
(-1350 1675);
FORCEPROP 2 LAST $XR1 55 
J 0
(-1041 1675);
DISPLAY 0.638298 (-1041 1675);
PAINT MONO (-1041 1675);
FORCEPROP 2 LAST $XR0 156 
J 0
(-1161 1675);
DISPLAY 0.638298 (-1161 1675);
PAINT MONO (-1161 1675);
FORCEPROP 1 LAST OFFPAGE TRUE
J 0
(-1025 1550);
PAINT GREEN (-1025 1550);
DISPLAY INVISIBLE (-1025 1550);
FORCEPROP 2 LAST PATH I19
J 0
(-1150 1725);
DISPLAY 1.021277 (-1150 1725);
PAINT ORANGE (-1150 1725);
DISPLAY INVISIBLE (-1150 1725);
FORCEPROP 1 LAST COMMENT_BODY TRUE
J 0
(-1395 1580);
DISPLAY 1.170213 (-1395 1580);
PAINT GREEN (-1395 1580);
DISPLAY INVISIBLE (-1395 1580);
FORCEPROP 2 LAST CDS_LIB mstr_standard
J 0
(-1350 1675);
PAINT ORANGE (-1350 1675);
DISPLAY INVISIBLE (-1350 1675);
FORCEADD OFFPAGE..2
(475 3200);
FORCEPROP 2 LAST $XR0 21 
J 0
(664 3200);
DISPLAY 0.638298 (664 3200);
PAINT MONO (664 3200);
FORCEPROP 1 LAST OFFPAGE TRUE
J 0
(800 3075);
PAINT GREEN (800 3075);
DISPLAY INVISIBLE (800 3075);
FORCEPROP 2 LAST PATH I2
J 0
(675 3250);
DISPLAY 1.021277 (675 3250);
PAINT ORANGE (675 3250);
DISPLAY INVISIBLE (675 3250);
FORCEPROP 1 LAST COMMENT_BODY TRUE
J 0
(430 3105);
DISPLAY 1.170213 (430 3105);
PAINT GREEN (430 3105);
DISPLAY INVISIBLE (430 3105);
FORCEPROP 2 LAST CDS_LIB mstr_standard
J 0
(475 3200);
PAINT ORANGE (475 3200);
DISPLAY INVISIBLE (475 3200);
FORCEADD OFFPAGE..2
(-1350 1475);
FORCEPROP 2 LAST $XR0 55 
J 0
(-1161 1475);
DISPLAY 0.638298 (-1161 1475);
PAINT MONO (-1161 1475);
FORCEPROP 2 LAST PATH I20
J 0
(-1150 1525);
DISPLAY 1.021277 (-1150 1525);
PAINT ORANGE (-1150 1525);
DISPLAY INVISIBLE (-1150 1525);
FORCEPROP 1 LAST OFFPAGE TRUE
J 0
(-1025 1350);
PAINT GREEN (-1025 1350);
DISPLAY INVISIBLE (-1025 1350);
FORCEPROP 2 LAST CDS_LIB mstr_standard
J 0
(-1350 1475);
PAINT ORANGE (-1350 1475);
DISPLAY INVISIBLE (-1350 1475);
FORCEPROP 1 LAST COMMENT_BODY TRUE
J 0
(-1395 1380);
DISPLAY 1.170213 (-1395 1380);
PAINT GREEN (-1395 1380);
DISPLAY INVISIBLE (-1395 1380);
FORCEADD OFFPAGE..2
(-1350 1275);
FORCEPROP 2 LAST $XR0 55 
J 0
(-1161 1275);
DISPLAY 0.638298 (-1161 1275);
PAINT MONO (-1161 1275);
FORCEPROP 2 LAST PATH I23
J 0
(-1150 1325);
DISPLAY 1.021277 (-1150 1325);
PAINT ORANGE (-1150 1325);
DISPLAY INVISIBLE (-1150 1325);
FORCEPROP 1 LAST OFFPAGE TRUE
J 0
(-1025 1150);
PAINT GREEN (-1025 1150);
DISPLAY INVISIBLE (-1025 1150);
FORCEPROP 2 LAST CDS_LIB mstr_standard
J 0
(-1350 1275);
PAINT ORANGE (-1350 1275);
DISPLAY INVISIBLE (-1350 1275);
FORCEPROP 1 LAST COMMENT_BODY TRUE
J 0
(-1395 1180);
DISPLAY 1.170213 (-1395 1180);
PAINT GREEN (-1395 1180);
DISPLAY INVISIBLE (-1395 1180);
FORCEADD RES..1
(-2450 1675);
FORCEPROP 1 LAST WATTAGE 1/16W
J 2
(-2400 1625);
DISPLAY 0.617021 (-2400 1625);
PAINT SKYBLUE (-2400 1625);
FORCEPROP 1 LASTPIN (-2550 1675) $PN 1
J 0
(-2538 1687);
DISPLAY 0.617021 (-2538 1687);
PAINT MONO (-2538 1687);
FORCEPROP 1 LASTPIN (-2350 1675) $PN 2
J 0
(-2388 1687);
DISPLAY 0.617021 (-2388 1687);
PAINT MONO (-2388 1687);
FORCEPROP 1 LAST TOLERANCE 1.0%
J 0
(-2625 1625);
DISPLAY 0.617021 (-2625 1625);
PAINT SKYBLUE (-2625 1625);
FORCEPROP 1 LAST VALUE 240
J 2
(-2650 1625);
DISPLAY 0.617021 (-2650 1625);
PAINT SKYBLUE (-2650 1625);
FORCEPROP 1 LAST PACK_TYPE 0402
J 0
(-2375 1625);
DISPLAY 0.617021 (-2375 1625);
PAINT SKYBLUE (-2375 1625);
FORCEPROP 1 LAST LOCATION R3D16
J 0
(-2675 1675);
DISPLAY 0.617021 (-2675 1675);
PAINT AQUA (-2675 1675);
FORCEPROP 1 LAST MATERIAL EMPTY
J 0
(-2250 1625);
DISPLAY 0.617021 (-2250 1625);
PAINT RED (-2250 1625);
FORCEPROP 1 LAST PART_NUMBER G21796-294
J 0
(-2325 1675);
DISPLAY 0.617021 (-2325 1675);
PAINT BLUE (-2325 1675);
FORCEPROP 2 LAST ROOM PROC_SIDEBAND
J 0
(-2100 1775);
PAINT MONO (-2100 1775);
DISPLAY INVISIBLE (-2100 1775);
FORCEPROP 2 LAST SEC_TYPE 0402
J 0
(-2500 1875);
PAINT MONO (-2500 1875);
DISPLAY INVISIBLE (-2500 1875);
FORCEPROP 2 LAST SEC 1
J 0
(-2500 1875);
DISPLAY 0.936170 (-2500 1875);
PAINT MONO (-2500 1875);
DISPLAY INVISIBLE (-2500 1875);
FORCEPROP 1 LAST PATH I24
J 0
(-2500 1825);
DISPLAY 0.978723 (-2500 1825);
PAINT WHITE (-2500 1825);
DISPLAY INVISIBLE (-2500 1825);
FORCEPROP 2 LAST CDS_LIB mstr_discrete
J 0
(-2450 1675);
PAINT ORANGE (-2450 1675);
DISPLAY INVISIBLE (-2450 1675);
FORCEPROP 2 LAST BOM_COST PROC
J 0
(-2450 1675);
PAINT MONO (-2450 1675);
DISPLAY INVISIBLE (-2450 1675);
FORCEPROP 2 LAST CDS_LOCATION R3D16
J 0
(-2725 1700);
DISPLAY 0.617021 (-2725 1700);
PAINT AQUA (-2725 1700);
DISPLAY INVISIBLE (-2725 1700);
FORCEADD RES..1
(-2450 1475);
FORCEPROP 1 LAST PACK_TYPE 0402
J 0
(-2375 1425);
DISPLAY 0.617021 (-2375 1425);
PAINT SKYBLUE (-2375 1425);
FORCEPROP 1 LAST TOLERANCE 1.0%
J 0
(-2625 1425);
DISPLAY 0.617021 (-2625 1425);
PAINT SKYBLUE (-2625 1425);
FORCEPROP 1 LASTPIN (-2550 1475) $PN 1
J 0
(-2538 1487);
DISPLAY 0.617021 (-2538 1487);
PAINT MONO (-2538 1487);
FORCEPROP 1 LAST WATTAGE 1/16W
J 2
(-2400 1425);
DISPLAY 0.617021 (-2400 1425);
PAINT SKYBLUE (-2400 1425);
FORCEPROP 1 LASTPIN (-2350 1475) $PN 2
J 0
(-2388 1487);
DISPLAY 0.617021 (-2388 1487);
PAINT MONO (-2388 1487);
FORCEPROP 1 LAST LOCATION R3D23
J 0
(-2675 1475);
DISPLAY 0.617021 (-2675 1475);
PAINT AQUA (-2675 1475);
FORCEPROP 1 LAST VALUE 240
J 2
(-2650 1425);
DISPLAY 0.617021 (-2650 1425);
PAINT SKYBLUE (-2650 1425);
FORCEPROP 1 LAST MATERIAL EMPTY
J 0
(-2250 1425);
DISPLAY 0.617021 (-2250 1425);
PAINT RED (-2250 1425);
FORCEPROP 1 LAST PART_NUMBER G21796-294
J 0
(-2325 1475);
DISPLAY 0.617021 (-2325 1475);
PAINT BLUE (-2325 1475);
FORCEPROP 2 LAST ROOM PROC_SIDEBAND
J 0
(-2100 1575);
PAINT MONO (-2100 1575);
DISPLAY INVISIBLE (-2100 1575);
FORCEPROP 2 LAST $SEC 1
J 0
(-2500 1675);
DISPLAY 0.936170 (-2500 1675);
PAINT MONO (-2500 1675);
DISPLAY INVISIBLE (-2500 1675);
FORCEPROP 2 LAST CDS_SEC 1
J 0
(-2500 1675);
DISPLAY 1.404255 (-2500 1675);
PAINT ORANGE (-2500 1675);
DISPLAY INVISIBLE (-2500 1675);
FORCEPROP 1 LAST PATH I25
J 0
(-2500 1625);
DISPLAY 0.978723 (-2500 1625);
PAINT WHITE (-2500 1625);
DISPLAY INVISIBLE (-2500 1625);
FORCEPROP 2 LAST CDS_LIB mstr_discrete
J 0
(-2450 1475);
PAINT ORANGE (-2450 1475);
DISPLAY INVISIBLE (-2450 1475);
FORCEPROP 2 LAST BOM_COST PROC
J 0
(-2450 1475);
PAINT MONO (-2450 1475);
DISPLAY INVISIBLE (-2450 1475);
FORCEPROP 2 LAST CDS_LOCATION R3D23
J 0
(-2725 1500);
DISPLAY 0.617021 (-2725 1500);
PAINT AQUA (-2725 1500);
DISPLAY INVISIBLE (-2725 1500);
FORCEADD RES..1
(-2450 1275);
FORCEPROP 1 LAST WATTAGE 1/16W
J 2
(-2400 1225);
DISPLAY 0.617021 (-2400 1225);
PAINT SKYBLUE (-2400 1225);
FORCEPROP 1 LAST PACK_TYPE 0402
J 0
(-2375 1225);
DISPLAY 0.617021 (-2375 1225);
PAINT SKYBLUE (-2375 1225);
FORCEPROP 1 LASTPIN (-2350 1275) $PN 2
J 0
(-2388 1287);
DISPLAY 0.617021 (-2388 1287);
PAINT MONO (-2388 1287);
FORCEPROP 1 LAST PART_NUMBER G21796-294
J 0
(-2325 1275);
DISPLAY 0.617021 (-2325 1275);
PAINT BLUE (-2325 1275);
FORCEPROP 1 LASTPIN (-2550 1275) $PN 1
J 0
(-2538 1287);
DISPLAY 0.617021 (-2538 1287);
PAINT MONO (-2538 1287);
FORCEPROP 1 LAST VALUE 240
J 2
(-2650 1225);
DISPLAY 0.617021 (-2650 1225);
PAINT SKYBLUE (-2650 1225);
FORCEPROP 1 LAST LOCATION R3D26
J 0
(-2675 1275);
DISPLAY 0.617021 (-2675 1275);
PAINT AQUA (-2675 1275);
FORCEPROP 1 LAST MATERIAL EMPTY
J 0
(-2250 1225);
DISPLAY 0.617021 (-2250 1225);
PAINT RED (-2250 1225);
FORCEPROP 1 LAST TOLERANCE 1.0%
J 0
(-2625 1225);
DISPLAY 0.617021 (-2625 1225);
PAINT SKYBLUE (-2625 1225);
FORCEPROP 0 LAST ROOM PROC_SIDEBAND
J 0
(-2075 1425);
DISPLAY 1.021277 (-2075 1425);
PAINT ORANGE (-2075 1425);
DISPLAY INVISIBLE (-2075 1425);
FORCEPROP 1 LAST PATH I28
J 0
(-2500 1425);
DISPLAY 0.978723 (-2500 1425);
PAINT WHITE (-2500 1425);
DISPLAY INVISIBLE (-2500 1425);
FORCEPROP 2 LAST SEC 1
J 0
(-2500 1475);
DISPLAY 0.936170 (-2500 1475);
PAINT MONO (-2500 1475);
DISPLAY INVISIBLE (-2500 1475);
FORCEPROP 2 LAST SEC_TYPE 0402
J 0
(-2500 1475);
PAINT MONO (-2500 1475);
DISPLAY INVISIBLE (-2500 1475);
FORCEPROP 2 LAST CDS_LIB mstr_discrete
J 0
(-2450 1275);
PAINT ORANGE (-2450 1275);
DISPLAY INVISIBLE (-2450 1275);
FORCEPROP 2 LAST BOM_COST PROC
J 0
(-2450 1275);
PAINT MONO (-2450 1275);
DISPLAY INVISIBLE (-2450 1275);
FORCEPROP 2 LAST CDS_LOCATION R3D26
J 0
(-2725 1300);
DISPLAY 0.617021 (-2725 1300);
PAINT AQUA (-2725 1300);
DISPLAY INVISIBLE (-2725 1300);
FORCEADD RES..1
(-2475 4400);
FORCEPROP 1 LAST MATERIAL CHIP
J 0
(-2275 4350);
DISPLAY 0.617021 (-2275 4350);
PAINT SKYBLUE (-2275 4350);
FORCEPROP 1 LAST PACK_TYPE 0402
J 0
(-2400 4350);
DISPLAY 0.617021 (-2400 4350);
PAINT SKYBLUE (-2400 4350);
FORCEPROP 1 LASTPIN (-2375 4400) $PN 2
J 0
(-2413 4412);
DISPLAY 0.617021 (-2413 4412);
PAINT MONO (-2413 4412);
FORCEPROP 1 LASTPIN (-2575 4400) $PN 1
J 0
(-2563 4412);
DISPLAY 0.617021 (-2563 4412);
PAINT MONO (-2563 4412);
FORCEPROP 1 LAST WATTAGE 1/16W
J 2
(-2425 4350);
DISPLAY 0.617021 (-2425 4350);
PAINT SKYBLUE (-2425 4350);
FORCEPROP 1 LAST LOCATION R5D3
J 0
(-2700 4400);
DISPLAY 0.617021 (-2700 4400);
PAINT AQUA (-2700 4400);
FORCEPROP 1 LAST TOLERANCE 1.0%
J 0
(-2650 4350);
DISPLAY 0.617021 (-2650 4350);
PAINT SKYBLUE (-2650 4350);
FORCEPROP 1 LAST PART_NUMBER G21796-294
J 0
(-2350 4400);
DISPLAY 0.617021 (-2350 4400);
PAINT BLUE (-2350 4400);
FORCEPROP 1 LAST VALUE 240
J 2
(-2675 4350);
DISPLAY 0.617021 (-2675 4350);
PAINT SKYBLUE (-2675 4350);
FORCEPROP 1 LAST PATH I29
J 0
(-2525 4550);
DISPLAY 0.978723 (-2525 4550);
PAINT WHITE (-2525 4550);
DISPLAY INVISIBLE (-2525 4550);
FORCEPROP 2 LAST SEC 1
J 0
(-2525 4600);
DISPLAY 0.680851 (-2525 4600);
PAINT MONO (-2525 4600);
DISPLAY INVISIBLE (-2525 4600);
FORCEPROP 2 LAST SEC_TYPE 0402
J 0
(-2525 4600);
DISPLAY 1.021277 (-2525 4600);
PAINT ORANGE (-2525 4600);
DISPLAY INVISIBLE (-2525 4600);
FORCEPROP 2 LAST ROOM PROC_SIDEBAND
J 0
(-2125 4500);
PAINT MONO (-2125 4500);
DISPLAY INVISIBLE (-2125 4500);
FORCEPROP 2 LAST CDS_LIB mstr_discrete
J 0
(-2475 4400);
PAINT ORANGE (-2475 4400);
DISPLAY INVISIBLE (-2475 4400);
FORCEPROP 2 LAST BOM_COST PROC
J 0
(-2475 4400);
PAINT MONO (-2475 4400);
DISPLAY INVISIBLE (-2475 4400);
FORCEPROP 2 LAST CDS_LOCATION R5D3
J 0
(-2750 4425);
DISPLAY 0.617021 (-2750 4425);
PAINT AQUA (-2750 4425);
DISPLAY INVISIBLE (-2750 4425);
FORCEADD PVCCIO_CPU0..1
(-2975 4550);
FORCEPROP 3 LASTPIN (-2975 4500) SIG_NAME PVCCIO_CPU0\g
J 0
(-2965 4510);
DISPLAY 0.659574 (-2965 4510);
PAINT MONO (-2965 4510);
DISPLAY INVISIBLE (-2965 4510);
FORCEPROP 1 LAST HDL_POWER PVCCIO_CPU0
J 1
(-2975 4600);
DISPLAY 0.872340 (-2975 4600);
PAINT GREEN (-2975 4600);
DISPLAY INVISIBLE (-2975 4600);
FORCEPROP 1 LAST PATH I30
J 0
(-2925 4575);
DISPLAY 0.872340 (-2925 4575);
PAINT AQUA (-2925 4575);
DISPLAY INVISIBLE (-2925 4575);
FORCEPROP 2 LAST CDS_LIB mstr_symbols
J 0
(-2975 4550);
PAINT ORANGE (-2975 4550);
DISPLAY INVISIBLE (-2975 4550);
FORCEPROP 1 LAST BODY_TYPE PLUMBING
J 0
(-3020 4507);
DISPLAY 0.340426 (-3020 4507);
PAINT GREEN (-3020 4507);
DISPLAY INVISIBLE (-3020 4507);
FORCEPROP 1 LAST VOLTAGE 1.1V
J 0
(-3020 4507);
DISPLAY 0.340426 (-3020 4507);
PAINT SKYBLUE (-3020 4507);
DISPLAY INVISIBLE (-3020 4507);
FORCEADD RES..1
(-2475 4200);
FORCEPROP 1 LAST LOCATION R6D7
J 0
(-2700 4200);
DISPLAY 0.617021 (-2700 4200);
PAINT AQUA (-2700 4200);
FORCEPROP 1 LAST VALUE 240
J 2
(-2675 4150);
DISPLAY 0.617021 (-2675 4150);
PAINT SKYBLUE (-2675 4150);
FORCEPROP 1 LAST TOLERANCE 1.0%
J 0
(-2650 4150);
DISPLAY 0.617021 (-2650 4150);
PAINT SKYBLUE (-2650 4150);
FORCEPROP 1 LASTPIN (-2575 4200) $PN 1
J 0
(-2563 4212);
DISPLAY 0.617021 (-2563 4212);
PAINT MONO (-2563 4212);
FORCEPROP 1 LASTPIN (-2375 4200) $PN 2
J 0
(-2413 4212);
DISPLAY 0.617021 (-2413 4212);
PAINT MONO (-2413 4212);
FORCEPROP 1 LAST WATTAGE 1/16W
J 2
(-2425 4150);
DISPLAY 0.617021 (-2425 4150);
PAINT SKYBLUE (-2425 4150);
FORCEPROP 1 LAST MATERIAL EMPTY
J 0
(-2275 4150);
DISPLAY 0.617021 (-2275 4150);
PAINT RED (-2275 4150);
FORCEPROP 1 LAST PACK_TYPE 0402
J 0
(-2400 4150);
DISPLAY 0.617021 (-2400 4150);
PAINT SKYBLUE (-2400 4150);
FORCEPROP 1 LAST PART_NUMBER G21796-294
J 0
(-2350 4200);
DISPLAY 0.617021 (-2350 4200);
PAINT BLUE (-2350 4200);
FORCEPROP 2 LAST ROOM PROC_SIDEBAND
J 0
(-2125 4300);
PAINT MONO (-2125 4300);
DISPLAY INVISIBLE (-2125 4300);
FORCEPROP 2 LAST SEC_TYPE 0402
J 0
(-2525 4400);
DISPLAY 1.021277 (-2525 4400);
PAINT ORANGE (-2525 4400);
DISPLAY INVISIBLE (-2525 4400);
FORCEPROP 2 LAST SEC 1
J 0
(-2525 4400);
DISPLAY 0.680851 (-2525 4400);
PAINT MONO (-2525 4400);
DISPLAY INVISIBLE (-2525 4400);
FORCEPROP 1 LAST PATH I31
J 0
(-2525 4350);
DISPLAY 0.978723 (-2525 4350);
PAINT WHITE (-2525 4350);
DISPLAY INVISIBLE (-2525 4350);
FORCEPROP 2 LAST BOM_COST PROC
J 0
(-2475 4200);
PAINT MONO (-2475 4200);
DISPLAY INVISIBLE (-2475 4200);
FORCEPROP 2 LAST CDS_LIB mstr_discrete
J 0
(-2475 4200);
PAINT ORANGE (-2475 4200);
DISPLAY INVISIBLE (-2475 4200);
FORCEPROP 2 LAST CDS_LOCATION R6D7
J 0
(-2750 4225);
DISPLAY 0.617021 (-2750 4225);
PAINT AQUA (-2750 4225);
DISPLAY INVISIBLE (-2750 4225);
FORCEADD RES..1
(-2475 3800);
FORCEPROP 1 LASTPIN (-2575 3800) $PN 1
J 0
(-2563 3812);
DISPLAY 0.617021 (-2563 3812);
PAINT MONO (-2563 3812);
FORCEPROP 1 LASTPIN (-2375 3800) $PN 2
J 0
(-2413 3812);
DISPLAY 0.617021 (-2413 3812);
PAINT MONO (-2413 3812);
FORCEPROP 1 LAST WATTAGE 1/16W
J 2
(-2425 3750);
DISPLAY 0.617021 (-2425 3750);
PAINT SKYBLUE (-2425 3750);
FORCEPROP 1 LAST MATERIAL EMPTY
J 0
(-2275 3750);
DISPLAY 0.617021 (-2275 3750);
PAINT RED (-2275 3750);
FORCEPROP 1 LAST TOLERANCE 1.0%
J 0
(-2650 3750);
DISPLAY 0.617021 (-2650 3750);
PAINT SKYBLUE (-2650 3750);
FORCEPROP 1 LAST VALUE 240
J 2
(-2675 3750);
DISPLAY 0.617021 (-2675 3750);
PAINT SKYBLUE (-2675 3750);
FORCEPROP 1 LAST LOCATION R6D13
J 0
(-2700 3800);
DISPLAY 0.617021 (-2700 3800);
PAINT AQUA (-2700 3800);
FORCEPROP 1 LAST PACK_TYPE 0402
J 0
(-2400 3750);
DISPLAY 0.617021 (-2400 3750);
PAINT SKYBLUE (-2400 3750);
FORCEPROP 1 LAST PART_NUMBER G21796-294
J 0
(-2350 3800);
DISPLAY 0.617021 (-2350 3800);
PAINT BLUE (-2350 3800);
FORCEPROP 0 LAST ROOM PROC_SIDEBAND
J 0
(-2100 3950);
DISPLAY 1.021277 (-2100 3950);
PAINT ORANGE (-2100 3950);
DISPLAY INVISIBLE (-2100 3950);
FORCEPROP 2 LAST SEC_TYPE 0402
J 0
(-2525 4000);
DISPLAY 1.021277 (-2525 4000);
PAINT ORANGE (-2525 4000);
DISPLAY INVISIBLE (-2525 4000);
FORCEPROP 2 LAST SEC 1
J 0
(-2525 4000);
DISPLAY 0.680851 (-2525 4000);
PAINT MONO (-2525 4000);
DISPLAY INVISIBLE (-2525 4000);
FORCEPROP 1 LAST PATH I33
J 0
(-2525 3950);
DISPLAY 0.978723 (-2525 3950);
PAINT WHITE (-2525 3950);
DISPLAY INVISIBLE (-2525 3950);
FORCEPROP 2 LAST CDS_LIB mstr_discrete
J 0
(-2475 3800);
PAINT ORANGE (-2475 3800);
DISPLAY INVISIBLE (-2475 3800);
FORCEPROP 2 LAST BOM_COST PROC
J 0
(-2475 3800);
PAINT MONO (-2475 3800);
DISPLAY INVISIBLE (-2475 3800);
FORCEPROP 2 LAST CDS_LOCATION R6D13
J 0
(-2750 3825);
DISPLAY 0.617021 (-2750 3825);
PAINT AQUA (-2750 3825);
DISPLAY INVISIBLE (-2750 3825);
FORCEADD OFFPAGE..1
R 2
(525 4400);
FORCEPROP 2 LAST $XR0 21 
J 0
(711 4400);
DISPLAY 0.638298 (711 4400);
PAINT MONO (711 4400);
FORCEPROP 2 LAST CDS_LIB mstr_standard
J 2
(525 4400);
PAINT ORANGE (525 4400);
DISPLAY INVISIBLE (525 4400);
FORCEPROP 1 LAST OFFPAGE TRUE
J 2
(200 4275);
DISPLAY 0.872340 (200 4275);
PAINT GREEN (200 4275);
DISPLAY INVISIBLE (200 4275);
FORCEPROP 1 LAST COMMENT_BODY TRUE
J 2
(400 4300);
DISPLAY 0.872340 (400 4300);
PAINT GREEN (400 4300);
DISPLAY INVISIBLE (400 4300);
FORCEPROP 2 LAST PATH I45
J 2
(325 4450);
DISPLAY 1.021277 (325 4450);
PAINT ORANGE (325 4450);
DISPLAY INVISIBLE (325 4450);
FORCEADD OFFPAGE..1
R 2
(525 4200);
FORCEPROP 2 LAST $XR0 21 
J 0
(711 4200);
DISPLAY 0.638298 (711 4200);
PAINT MONO (711 4200);
FORCEPROP 2 LAST CDS_LIB mstr_standard
J 2
(525 4200);
PAINT ORANGE (525 4200);
DISPLAY INVISIBLE (525 4200);
FORCEPROP 1 LAST COMMENT_BODY TRUE
J 2
(400 4100);
DISPLAY 0.872340 (400 4100);
PAINT GREEN (400 4100);
DISPLAY INVISIBLE (400 4100);
FORCEPROP 2 LAST PATH I46
J 2
(325 4250);
DISPLAY 1.021277 (325 4250);
PAINT ORANGE (325 4250);
DISPLAY INVISIBLE (325 4250);
FORCEPROP 1 LAST OFFPAGE TRUE
J 2
(200 4075);
DISPLAY 0.872340 (200 4075);
PAINT GREEN (200 4075);
DISPLAY INVISIBLE (200 4075);
FORCEADD RES..1
(-475 4400);
FORCEPROP 1 LAST MATERIAL EMPTY
J 0
(-275 4350);
DISPLAY 0.617021 (-275 4350);
PAINT RED (-275 4350);
FORCEPROP 1 LAST PART_NUMBER G21796-294
J 0
(-350 4400);
DISPLAY 0.617021 (-350 4400);
PAINT BLUE (-350 4400);
FORCEPROP 1 LAST LOCATION R6D15
J 0
(-725 4400);
DISPLAY 0.617021 (-725 4400);
PAINT AQUA (-725 4400);
FORCEPROP 1 LAST TOLERANCE 1.0%
J 0
(-650 4350);
DISPLAY 0.617021 (-650 4350);
PAINT SKYBLUE (-650 4350);
FORCEPROP 1 LAST PACK_TYPE 0402
J 0
(-400 4350);
DISPLAY 0.617021 (-400 4350);
PAINT SKYBLUE (-400 4350);
FORCEPROP 1 LAST VALUE 240
J 2
(-675 4350);
DISPLAY 0.617021 (-675 4350);
PAINT SKYBLUE (-675 4350);
FORCEPROP 1 LASTPIN (-375 4400) $PN 2
J 0
(-413 4412);
DISPLAY 0.617021 (-413 4412);
PAINT ORANGE (-413 4412);
FORCEPROP 1 LAST WATTAGE 1/16W
J 2
(-425 4350);
DISPLAY 0.617021 (-425 4350);
PAINT SKYBLUE (-425 4350);
FORCEPROP 1 LASTPIN (-575 4400) $PN 1
J 0
(-563 4412);
DISPLAY 0.617021 (-563 4412);
PAINT ORANGE (-563 4412);
FORCEPROP 2 LAST ROOM PROC_SIDEBAND
J 0
(-100 4500);
PAINT MONO (-100 4500);
DISPLAY INVISIBLE (-100 4500);
FORCEPROP 2 LAST SEC 1
J 0
(-525 4600);
DISPLAY 0.680851 (-525 4600);
PAINT MONO (-525 4600);
DISPLAY INVISIBLE (-525 4600);
FORCEPROP 2 LAST SEC_TYPE 0402
J 0
(-525 4600);
DISPLAY 1.021277 (-525 4600);
PAINT ORANGE (-525 4600);
DISPLAY INVISIBLE (-525 4600);
FORCEPROP 1 LAST PATH I48
J 0
(-525 4550);
DISPLAY 0.978723 (-525 4550);
PAINT WHITE (-525 4550);
DISPLAY INVISIBLE (-525 4550);
FORCEPROP 2 LAST CDS_LIB mstr_discrete
J 0
(-475 4400);
PAINT ORANGE (-475 4400);
DISPLAY INVISIBLE (-475 4400);
FORCEPROP 2 LAST BOM_COST PROC
J 0
(-475 4400);
PAINT MONO (-475 4400);
DISPLAY INVISIBLE (-475 4400);
FORCEPROP 2 LAST CDS_LOCATION R6D15
J 0
(-750 4425);
DISPLAY 0.617021 (-750 4425);
PAINT AQUA (-750 4425);
DISPLAY INVISIBLE (-750 4425);
FORCEADD RES..1
(-475 4200);
FORCEPROP 1 LAST MATERIAL EMPTY
J 0
(-275 4150);
DISPLAY 0.617021 (-275 4150);
PAINT RED (-275 4150);
FORCEPROP 1 LAST PART_NUMBER G21796-294
J 0
(-350 4200);
DISPLAY 0.617021 (-350 4200);
PAINT BLUE (-350 4200);
FORCEPROP 1 LAST TOLERANCE 1.0%
J 0
(-650 4150);
DISPLAY 0.617021 (-650 4150);
PAINT SKYBLUE (-650 4150);
FORCEPROP 1 LAST LOCATION R6D10
J 0
(-725 4200);
DISPLAY 0.617021 (-725 4200);
PAINT AQUA (-725 4200);
FORCEPROP 1 LASTPIN (-375 4200) $PN 2
J 0
(-413 4212);
DISPLAY 0.617021 (-413 4212);
PAINT MONO (-413 4212);
FORCEPROP 1 LAST WATTAGE 1/16W
J 2
(-425 4150);
DISPLAY 0.617021 (-425 4150);
PAINT SKYBLUE (-425 4150);
FORCEPROP 1 LAST PACK_TYPE 0402
J 0
(-400 4150);
DISPLAY 0.617021 (-400 4150);
PAINT SKYBLUE (-400 4150);
FORCEPROP 1 LASTPIN (-575 4200) $PN 1
J 0
(-563 4212);
DISPLAY 0.617021 (-563 4212);
PAINT MONO (-563 4212);
FORCEPROP 1 LAST VALUE 240
J 2
(-675 4150);
DISPLAY 0.617021 (-675 4150);
PAINT SKYBLUE (-675 4150);
FORCEPROP 2 LAST CDS_LOCATION R6D10
J 0
(-750 4225);
DISPLAY 0.617021 (-750 4225);
PAINT AQUA (-750 4225);
DISPLAY INVISIBLE (-750 4225);
FORCEPROP 2 LAST BOM_COST PROC
J 0
(-475 4200);
PAINT MONO (-475 4200);
DISPLAY INVISIBLE (-475 4200);
FORCEPROP 2 LAST CDS_LIB mstr_discrete
J 0
(-475 4200);
PAINT ORANGE (-475 4200);
DISPLAY INVISIBLE (-475 4200);
FORCEPROP 1 LAST PATH I49
J 0
(-525 4350);
DISPLAY 0.978723 (-525 4350);
PAINT WHITE (-525 4350);
DISPLAY INVISIBLE (-525 4350);
FORCEPROP 2 LAST SEC_TYPE 0402
J 0
(-525 4400);
DISPLAY 1.021277 (-525 4400);
PAINT ORANGE (-525 4400);
DISPLAY INVISIBLE (-525 4400);
FORCEPROP 2 LAST SEC 1
J 0
(-525 4400);
DISPLAY 0.680851 (-525 4400);
PAINT MONO (-525 4400);
DISPLAY INVISIBLE (-525 4400);
FORCEPROP 2 LAST ROOM PROC_SIDEBAND
J 0
(-100 4300);
PAINT MONO (-100 4300);
DISPLAY INVISIBLE (-100 4300);
FORCEADD GND..1
(-900 2600);
FORCEPROP 3 LASTPIN (-900 2650) SIG_NAME GND\g
J 0
(-890 2660);
DISPLAY 0.659574 (-890 2660);
PAINT MONO (-890 2660);
DISPLAY INVISIBLE (-890 2660);
FORCEPROP 1 LAST PATH I5
J 0
(-825 2600);
DISPLAY 0.872340 (-825 2600);
PAINT AQUA (-825 2600);
DISPLAY INVISIBLE (-825 2600);
FORCEPROP 1 LAST HDL_POWER GND
J 0
(-900 2750);
DISPLAY 0.872340 (-900 2750);
PAINT GREEN (-900 2750);
DISPLAY INVISIBLE (-900 2750);
FORCEPROP 2 LAST CDS_LIB mstr_symbols
J 0
(-900 2600);
PAINT ORANGE (-900 2600);
DISPLAY INVISIBLE (-900 2600);
FORCEPROP 1 LAST VOLTAGE 0
J 0
(-900 2600);
PAINT SKYBLUE (-900 2600);
DISPLAY INVISIBLE (-900 2600);
FORCEPROP 1 LAST BODY_TYPE PLUMBING
J 0
(-945 2557);
DISPLAY 0.340426 (-945 2557);
PAINT GREEN (-945 2557);
DISPLAY INVISIBLE (-945 2557);
FORCEPROP 1 LAST SIZE 1B
J 0
(-825 2550);
DISPLAY 0.872340 (-825 2550);
PAINT GREEN (-825 2550);
DISPLAY INVISIBLE (-825 2550);
FORCEADD PVCCIO_CPU0..1
(-825 4625);
FORCEPROP 3 LASTPIN (-825 4575) SIG_NAME PVCCIO_CPU0\g
J 0
(-815 4585);
DISPLAY 0.659574 (-815 4585);
PAINT MONO (-815 4585);
DISPLAY INVISIBLE (-815 4585);
FORCEPROP 2 LAST CDS_LIB mstr_symbols
J 0
(-825 4625);
PAINT ORANGE (-825 4625);
DISPLAY INVISIBLE (-825 4625);
FORCEPROP 1 LAST PATH I51
J 0
(-775 4650);
DISPLAY 0.872340 (-775 4650);
PAINT AQUA (-775 4650);
DISPLAY INVISIBLE (-775 4650);
FORCEPROP 1 LAST HDL_POWER PVCCIO_CPU0
J 1
(-825 4675);
DISPLAY 0.872340 (-825 4675);
PAINT GREEN (-825 4675);
DISPLAY INVISIBLE (-825 4675);
FORCEPROP 1 LAST BODY_TYPE PLUMBING
J 0
(-870 4582);
DISPLAY 0.340426 (-870 4582);
PAINT GREEN (-870 4582);
DISPLAY INVISIBLE (-870 4582);
FORCEPROP 1 LAST VOLTAGE 1.1V
J 0
(-870 4582);
DISPLAY 0.340426 (-870 4582);
PAINT SKYBLUE (-870 4582);
DISPLAY INVISIBLE (-870 4582);
FORCEADD RES..1
(-2475 3600);
FORCEPROP 1 LAST VALUE 240
J 2
(-2675 3550);
DISPLAY 0.617021 (-2675 3550);
PAINT SKYBLUE (-2675 3550);
FORCEPROP 1 LASTPIN (-2575 3600) $PN 1
J 0
(-2563 3612);
DISPLAY 0.617021 (-2563 3612);
PAINT ORANGE (-2563 3612);
FORCEPROP 1 LAST TOLERANCE 1.0%
J 0
(-2650 3550);
DISPLAY 0.617021 (-2650 3550);
PAINT SKYBLUE (-2650 3550);
FORCEPROP 1 LAST LOCATION R6D14
J 0
(-2700 3600);
DISPLAY 0.617021 (-2700 3600);
PAINT AQUA (-2700 3600);
FORCEPROP 1 LAST MATERIAL EMPTY
J 0
(-2275 3550);
DISPLAY 0.617021 (-2275 3550);
PAINT RED (-2275 3550);
FORCEPROP 1 LAST PACK_TYPE 0402
J 0
(-2400 3550);
DISPLAY 0.617021 (-2400 3550);
PAINT SKYBLUE (-2400 3550);
FORCEPROP 1 LAST PART_NUMBER G21796-294
J 0
(-2350 3600);
DISPLAY 0.617021 (-2350 3600);
PAINT BLUE (-2350 3600);
FORCEPROP 1 LAST WATTAGE 1/16W
J 2
(-2425 3550);
DISPLAY 0.617021 (-2425 3550);
PAINT SKYBLUE (-2425 3550);
FORCEPROP 1 LASTPIN (-2375 3600) $PN 2
J 0
(-2413 3612);
DISPLAY 0.617021 (-2413 3612);
PAINT ORANGE (-2413 3612);
FORCEPROP 2 LAST ROOM PROC_SIDEBAND
J 0
(-2125 3700);
PAINT MONO (-2125 3700);
DISPLAY INVISIBLE (-2125 3700);
FORCEPROP 2 LAST SEC_TYPE 0402
J 0
(-2525 3800);
DISPLAY 1.021277 (-2525 3800);
PAINT ORANGE (-2525 3800);
DISPLAY INVISIBLE (-2525 3800);
FORCEPROP 1 LAST PATH I52
J 0
(-2525 3750);
DISPLAY 0.978723 (-2525 3750);
PAINT WHITE (-2525 3750);
DISPLAY INVISIBLE (-2525 3750);
FORCEPROP 2 LAST SEC 1
J 0
(-2525 3800);
DISPLAY 0.680851 (-2525 3800);
PAINT MONO (-2525 3800);
DISPLAY INVISIBLE (-2525 3800);
FORCEPROP 2 LAST BOM_COST PROC
J 0
(-2475 3600);
PAINT MONO (-2475 3600);
DISPLAY INVISIBLE (-2475 3600);
FORCEPROP 2 LAST CDS_LIB mstr_discrete
J 0
(-2475 3600);
PAINT ORANGE (-2475 3600);
DISPLAY INVISIBLE (-2475 3600);
FORCEPROP 2 LAST CDS_LOCATION R6D14
J 0
(-2775 3625);
DISPLAY 0.617021 (-2775 3625);
PAINT AQUA (-2775 3625);
DISPLAY INVISIBLE (-2775 3625);
FORCEADD RES..1
(-2475 3400);
FORCEPROP 1 LASTPIN (-2575 3400) $PN 1
J 0
(-2563 3412);
DISPLAY 0.617021 (-2563 3412);
PAINT ORANGE (-2563 3412);
FORCEPROP 1 LAST PACK_TYPE 0402
J 0
(-2400 3350);
DISPLAY 0.617021 (-2400 3350);
PAINT SKYBLUE (-2400 3350);
FORCEPROP 1 LASTPIN (-2375 3400) $PN 2
J 0
(-2413 3412);
DISPLAY 0.617021 (-2413 3412);
PAINT ORANGE (-2413 3412);
FORCEPROP 1 LAST MATERIAL CHIP
J 0
(-2275 3350);
DISPLAY 0.617021 (-2275 3350);
PAINT SKYBLUE (-2275 3350);
FORCEPROP 1 LAST WATTAGE 1/16W
J 2
(-2425 3350);
DISPLAY 0.617021 (-2425 3350);
PAINT SKYBLUE (-2425 3350);
FORCEPROP 1 LAST PART_NUMBER G21796-294
J 0
(-2350 3400);
DISPLAY 0.617021 (-2350 3400);
PAINT BLUE (-2350 3400);
FORCEPROP 1 LAST TOLERANCE 1.0%
J 0
(-2650 3350);
DISPLAY 0.617021 (-2650 3350);
PAINT SKYBLUE (-2650 3350);
FORCEPROP 1 LAST VALUE 240
J 2
(-2675 3350);
DISPLAY 0.617021 (-2675 3350);
PAINT SKYBLUE (-2675 3350);
FORCEPROP 1 LAST LOCATION R4P14
J 0
(-2700 3400);
DISPLAY 0.617021 (-2700 3400);
PAINT AQUA (-2700 3400);
FORCEPROP 2 LAST CDS_LOCATION R4P14
J 0
(-2725 3425);
DISPLAY 0.617021 (-2725 3425);
PAINT AQUA (-2725 3425);
DISPLAY INVISIBLE (-2725 3425);
FORCEPROP 2 LAST CDS_LIB mstr_discrete
J 0
(-2475 3400);
PAINT ORANGE (-2475 3400);
DISPLAY INVISIBLE (-2475 3400);
FORCEPROP 2 LAST BOM_COST PROC
J 0
(-2475 3400);
PAINT MONO (-2475 3400);
DISPLAY INVISIBLE (-2475 3400);
FORCEPROP 1 LAST PATH I53
J 0
(-2525 3550);
DISPLAY 0.978723 (-2525 3550);
PAINT WHITE (-2525 3550);
DISPLAY INVISIBLE (-2525 3550);
FORCEPROP 0 LAST ROOM PROC_SIDEBAND
J 0
(-2100 3550);
DISPLAY 1.021277 (-2100 3550);
PAINT ORANGE (-2100 3550);
DISPLAY INVISIBLE (-2100 3550);
FORCEPROP 2 LAST SEC_TYPE 0402
J 0
(-2525 3600);
DISPLAY 1.021277 (-2525 3600);
PAINT ORANGE (-2525 3600);
DISPLAY INVISIBLE (-2525 3600);
FORCEPROP 2 LAST SEC 1
J 0
(-2525 3600);
DISPLAY 0.680851 (-2525 3600);
PAINT MONO (-2525 3600);
DISPLAY INVISIBLE (-2525 3600);
FORCEADD OFFPAGE..2
(-1300 3600);
FORCEPROP 2 LAST $XR0 21 
J 0
(-1111 3600);
DISPLAY 0.638298 (-1111 3600);
PAINT MONO (-1111 3600);
FORCEPROP 1 LAST OFFPAGE TRUE
J 0
(-975 3475);
PAINT GREEN (-975 3475);
DISPLAY INVISIBLE (-975 3475);
FORCEPROP 2 LAST PATH I54
J 0
(-1125 3675);
DISPLAY 1.021277 (-1125 3675);
PAINT ORANGE (-1125 3675);
DISPLAY INVISIBLE (-1125 3675);
FORCEPROP 2 LAST CDS_LIB mstr_standard
J 0
(-1300 3600);
PAINT ORANGE (-1300 3600);
DISPLAY INVISIBLE (-1300 3600);
FORCEPROP 1 LAST COMMENT_BODY TRUE
J 0
(-1345 3505);
DISPLAY 1.170213 (-1345 3505);
PAINT GREEN (-1345 3505);
DISPLAY INVISIBLE (-1345 3505);
FORCEADD OFFPAGE..2
(-1300 3400);
FORCEPROP 2 LAST $XR0 21 
J 0
(-1111 3400);
DISPLAY 0.638298 (-1111 3400);
PAINT MONO (-1111 3400);
FORCEPROP 1 LAST OFFPAGE TRUE
J 0
(-975 3275);
PAINT GREEN (-975 3275);
DISPLAY INVISIBLE (-975 3275);
FORCEPROP 2 LAST PATH I55
J 0
(-1125 3475);
DISPLAY 1.021277 (-1125 3475);
PAINT ORANGE (-1125 3475);
DISPLAY INVISIBLE (-1125 3475);
FORCEPROP 2 LAST CDS_LIB mstr_standard
J 0
(-1300 3400);
PAINT ORANGE (-1300 3400);
DISPLAY INVISIBLE (-1300 3400);
FORCEPROP 1 LAST COMMENT_BODY TRUE
J 0
(-1345 3305);
DISPLAY 1.170213 (-1345 3305);
PAINT GREEN (-1345 3305);
DISPLAY INVISIBLE (-1345 3305);
FORCEADD OFFPAGE..1
R 2
(500 1475);
FORCEPROP 2 LAST $XR0 55 
J 0
(686 1475);
DISPLAY 0.638298 (686 1475);
PAINT MONO (686 1475);
FORCEPROP 2 LAST PATH I56
J 2
(300 1525);
DISPLAY 1.021277 (300 1525);
PAINT ORANGE (300 1525);
DISPLAY INVISIBLE (300 1525);
FORCEPROP 1 LAST COMMENT_BODY TRUE
J 2
(375 1375);
DISPLAY 0.872340 (375 1375);
PAINT GREEN (375 1375);
DISPLAY INVISIBLE (375 1375);
FORCEPROP 2 LAST CDS_LIB mstr_standard
J 2
(500 1475);
PAINT ORANGE (500 1475);
DISPLAY INVISIBLE (500 1475);
FORCEPROP 1 LAST OFFPAGE TRUE
J 2
(175 1350);
DISPLAY 0.872340 (175 1350);
PAINT GREEN (175 1350);
DISPLAY INVISIBLE (175 1350);
FORCEADD OFFPAGE..1
R 2
(500 1675);
FORCEPROP 2 LAST $XR0 55 
J 0
(686 1675);
DISPLAY 0.638298 (686 1675);
PAINT MONO (686 1675);
FORCEPROP 2 LAST PATH I57
J 2
(300 1725);
DISPLAY 1.021277 (300 1725);
PAINT ORANGE (300 1725);
DISPLAY INVISIBLE (300 1725);
FORCEPROP 1 LAST COMMENT_BODY TRUE
J 2
(375 1575);
DISPLAY 0.872340 (375 1575);
PAINT GREEN (375 1575);
DISPLAY INVISIBLE (375 1575);
FORCEPROP 1 LAST OFFPAGE TRUE
J 2
(175 1550);
DISPLAY 0.872340 (175 1550);
PAINT GREEN (175 1550);
DISPLAY INVISIBLE (175 1550);
FORCEPROP 2 LAST CDS_LIB mstr_standard
J 2
(500 1675);
PAINT ORANGE (500 1675);
DISPLAY INVISIBLE (500 1675);
FORCEADD RES..1
(-425 1675);
FORCEPROP 1 LAST PACK_TYPE 0402
J 0
(-350 1625);
DISPLAY 0.617021 (-350 1625);
PAINT SKYBLUE (-350 1625);
FORCEPROP 1 LAST WATTAGE 1/16W
J 2
(-375 1625);
DISPLAY 0.617021 (-375 1625);
PAINT SKYBLUE (-375 1625);
FORCEPROP 1 LAST LOCATION R3D24
J 0
(-650 1675);
DISPLAY 0.617021 (-650 1675);
PAINT AQUA (-650 1675);
FORCEPROP 1 LASTPIN (-525 1675) $PN 1
J 0
(-513 1687);
DISPLAY 0.787234 (-513 1687);
PAINT ORANGE (-513 1687);
FORCEPROP 1 LAST VALUE 240
J 2
(-625 1625);
DISPLAY 0.617021 (-625 1625);
PAINT SKYBLUE (-625 1625);
FORCEPROP 1 LAST TOLERANCE 1.0%
J 0
(-600 1625);
DISPLAY 0.617021 (-600 1625);
PAINT SKYBLUE (-600 1625);
FORCEPROP 1 LAST PART_NUMBER G21796-294
J 0
(-300 1675);
DISPLAY 0.617021 (-300 1675);
PAINT BLUE (-300 1675);
FORCEPROP 1 LAST MATERIAL CHIP
J 0
(-225 1625);
DISPLAY 0.617021 (-225 1625);
PAINT SKYBLUE (-225 1625);
FORCEPROP 1 LASTPIN (-325 1675) $PN 2
J 0
(-363 1687);
DISPLAY 0.787234 (-363 1687);
PAINT ORANGE (-363 1687);
FORCEPROP 2 LAST SEC_TYPE 0402
J 0
(-475 1875);
DISPLAY 1.021277 (-475 1875);
PAINT ORANGE (-475 1875);
DISPLAY INVISIBLE (-475 1875);
FORCEPROP 2 LAST SEC 1
J 0
(-475 1875);
DISPLAY 0.680851 (-475 1875);
PAINT MONO (-475 1875);
DISPLAY INVISIBLE (-475 1875);
FORCEPROP 2 LAST CDS_LOCATION R3D24
J 0
(-650 1725);
DISPLAY 0.617021 (-650 1725);
PAINT AQUA (-650 1725);
DISPLAY INVISIBLE (-650 1725);
FORCEPROP 2 LAST CDS_LIB mstr_discrete
J 0
(-425 1675);
PAINT ORANGE (-425 1675);
DISPLAY INVISIBLE (-425 1675);
FORCEPROP 2 LAST BOM_COST PROC
J 0
(-425 1675);
PAINT MONO (-425 1675);
DISPLAY INVISIBLE (-425 1675);
FORCEPROP 1 LAST PATH I59
J 0
(-475 1825);
DISPLAY 0.978723 (-475 1825);
PAINT WHITE (-475 1825);
DISPLAY INVISIBLE (-475 1825);
FORCEPROP 2 LAST ROOM PROC_SIDEBAND
J 0
(-50 1775);
PAINT MONO (-50 1775);
DISPLAY INVISIBLE (-50 1775);
FORCEADD OFFPAGE..2
(-1300 4400);
FORCEPROP 2 LAST $XR0 21 
J 0
(-1111 4400);
DISPLAY 0.638298 (-1111 4400);
PAINT MONO (-1111 4400);
FORCEPROP 1 LAST OFFPAGE TRUE
J 0
(-975 4275);
PAINT GREEN (-975 4275);
DISPLAY INVISIBLE (-975 4275);
FORCEPROP 2 LAST PATH I6
J 0
(-1100 4450);
DISPLAY 1.021277 (-1100 4450);
PAINT ORANGE (-1100 4450);
DISPLAY INVISIBLE (-1100 4450);
FORCEPROP 2 LAST CDS_LIB mstr_standard
J 0
(-1300 4400);
PAINT ORANGE (-1300 4400);
DISPLAY INVISIBLE (-1300 4400);
FORCEPROP 1 LAST COMMENT_BODY TRUE
J 0
(-1345 4305);
DISPLAY 1.170213 (-1345 4305);
PAINT GREEN (-1345 4305);
DISPLAY INVISIBLE (-1345 4305);
FORCEADD RES..1
(-425 1475);
FORCEPROP 1 LAST WATTAGE 1/16W
J 2
(-375 1425);
DISPLAY 0.617021 (-375 1425);
PAINT SKYBLUE (-375 1425);
FORCEPROP 1 LAST MATERIAL EMPTY
J 0
(-225 1425);
DISPLAY 0.617021 (-225 1425);
PAINT RED (-225 1425);
FORCEPROP 1 LAST TOLERANCE 1.0%
J 0
(-600 1425);
DISPLAY 0.617021 (-600 1425);
PAINT SKYBLUE (-600 1425);
FORCEPROP 1 LASTPIN (-525 1475) $PN 1
J 0
(-513 1487);
DISPLAY 0.787234 (-513 1487);
PAINT ORANGE (-513 1487);
FORCEPROP 1 LAST LOCATION R3D17
J 0
(-650 1475);
DISPLAY 0.617021 (-650 1475);
PAINT AQUA (-650 1475);
FORCEPROP 1 LAST VALUE 240
J 2
(-625 1425);
DISPLAY 0.617021 (-625 1425);
PAINT SKYBLUE (-625 1425);
FORCEPROP 1 LAST PACK_TYPE 0402
J 0
(-350 1425);
DISPLAY 0.617021 (-350 1425);
PAINT SKYBLUE (-350 1425);
FORCEPROP 1 LASTPIN (-325 1475) $PN 2
J 0
(-363 1487);
DISPLAY 0.787234 (-363 1487);
PAINT ORANGE (-363 1487);
FORCEPROP 1 LAST PART_NUMBER G21796-294
J 0
(-300 1475);
DISPLAY 0.617021 (-300 1475);
PAINT BLUE (-300 1475);
FORCEPROP 2 LAST SEC_TYPE 0402
J 0
(-475 1675);
DISPLAY 1.021277 (-475 1675);
PAINT ORANGE (-475 1675);
DISPLAY INVISIBLE (-475 1675);
FORCEPROP 2 LAST SEC 1
J 0
(-475 1675);
DISPLAY 0.680851 (-475 1675);
PAINT MONO (-475 1675);
DISPLAY INVISIBLE (-475 1675);
FORCEPROP 2 LAST ROOM PROC_SIDEBAND
J 0
(-50 1575);
PAINT MONO (-50 1575);
DISPLAY INVISIBLE (-50 1575);
FORCEPROP 1 LAST PATH I60
J 0
(-475 1625);
DISPLAY 0.978723 (-475 1625);
PAINT WHITE (-475 1625);
DISPLAY INVISIBLE (-475 1625);
FORCEPROP 2 LAST BOM_COST PROC
J 0
(-425 1475);
PAINT MONO (-425 1475);
DISPLAY INVISIBLE (-425 1475);
FORCEPROP 2 LAST CDS_LIB mstr_discrete
J 0
(-425 1475);
PAINT ORANGE (-425 1475);
DISPLAY INVISIBLE (-425 1475);
FORCEPROP 2 LAST CDS_LOCATION R3D17
J 0
(-675 1525);
DISPLAY 0.617021 (-675 1525);
PAINT AQUA (-675 1525);
DISPLAY INVISIBLE (-675 1525);
FORCEADD PVCCIO_CPU1..1
(-2950 2050);
FORCEPROP 3 LASTPIN (-2950 2000) SIG_NAME PVCCIO_CPU1\g
J 0
(-2940 2010);
DISPLAY 0.659574 (-2940 2010);
PAINT MONO (-2940 2010);
DISPLAY INVISIBLE (-2940 2010);
FORCEPROP 1 LAST HDL_POWER PVCCIO_CPU1
J 1
(-2950 2100);
DISPLAY 0.872340 (-2950 2100);
PAINT GREEN (-2950 2100);
DISPLAY INVISIBLE (-2950 2100);
FORCEPROP 1 LAST PATH I62
J 0
(-2900 2075);
DISPLAY 0.872340 (-2900 2075);
PAINT AQUA (-2900 2075);
DISPLAY INVISIBLE (-2900 2075);
FORCEPROP 2 LAST CDS_LIB mstr_symbols
J 0
(-2950 2050);
PAINT ORANGE (-2950 2050);
DISPLAY INVISIBLE (-2950 2050);
FORCEPROP 1 LAST BODY_TYPE PLUMBING
J 0
(-2995 2007);
DISPLAY 0.340426 (-2995 2007);
PAINT GREEN (-2995 2007);
DISPLAY INVISIBLE (-2995 2007);
FORCEPROP 1 LAST VOLTAGE 1.1V
J 0
(-2995 2007);
DISPLAY 0.340426 (-2995 2007);
PAINT SKYBLUE (-2995 2007);
DISPLAY INVISIBLE (-2995 2007);
FORCEADD PVCCIO_CPU1..1
(-725 1825);
FORCEPROP 3 LASTPIN (-725 1775) SIG_NAME PVCCIO_CPU1\g
J 0
(-715 1785);
DISPLAY 0.659574 (-715 1785);
PAINT MONO (-715 1785);
DISPLAY INVISIBLE (-715 1785);
FORCEPROP 2 LAST CDS_LIB mstr_symbols
J 0
(-725 1825);
PAINT ORANGE (-725 1825);
DISPLAY INVISIBLE (-725 1825);
FORCEPROP 1 LAST PATH I63
J 0
(-675 1850);
DISPLAY 0.872340 (-675 1850);
PAINT AQUA (-675 1850);
DISPLAY INVISIBLE (-675 1850);
FORCEPROP 1 LAST HDL_POWER PVCCIO_CPU1
J 1
(-725 1875);
DISPLAY 0.872340 (-725 1875);
PAINT GREEN (-725 1875);
DISPLAY INVISIBLE (-725 1875);
FORCEPROP 1 LAST BODY_TYPE PLUMBING
J 0
(-770 1782);
DISPLAY 0.340426 (-770 1782);
PAINT GREEN (-770 1782);
DISPLAY INVISIBLE (-770 1782);
FORCEPROP 1 LAST VOLTAGE 1.1V
J 0
(-770 1782);
DISPLAY 0.340426 (-770 1782);
PAINT SKYBLUE (-770 1782);
DISPLAY INVISIBLE (-770 1782);
FORCEADD OFFPAGE..2
(-1325 1025);
FORCEPROP 2 LAST $XR0 55 
J 0
(-1136 1025);
DISPLAY 0.638298 (-1136 1025);
PAINT MONO (-1136 1025);
FORCEPROP 1 LAST OFFPAGE TRUE
J 0
(-1000 900);
PAINT GREEN (-1000 900);
DISPLAY INVISIBLE (-1000 900);
FORCEPROP 2 LAST PATH I64
J 0
(-1150 1100);
DISPLAY 1.021277 (-1150 1100);
PAINT ORANGE (-1150 1100);
DISPLAY INVISIBLE (-1150 1100);
FORCEPROP 2 LAST CDS_LIB mstr_standard
J 0
(-1325 1025);
PAINT ORANGE (-1325 1025);
DISPLAY INVISIBLE (-1325 1025);
FORCEPROP 1 LAST COMMENT_BODY TRUE
J 0
(-1370 930);
DISPLAY 1.170213 (-1370 930);
PAINT GREEN (-1370 930);
DISPLAY INVISIBLE (-1370 930);
FORCEADD RES..1
(-2450 1025);
FORCEPROP 1 LASTPIN (-2350 1025) $PN 2
J 0
(-2388 1037);
DISPLAY 0.617021 (-2388 1037);
PAINT ORANGE (-2388 1037);
FORCEPROP 1 LAST PACK_TYPE 0402
J 0
(-2375 975);
DISPLAY 0.617021 (-2375 975);
PAINT SKYBLUE (-2375 975);
FORCEPROP 1 LAST MATERIAL EMPTY
J 0
(-2250 975);
DISPLAY 0.617021 (-2250 975);
PAINT RED (-2250 975);
FORCEPROP 1 LAST WATTAGE 1/16W
J 2
(-2400 975);
DISPLAY 0.617021 (-2400 975);
PAINT SKYBLUE (-2400 975);
FORCEPROP 1 LASTPIN (-2550 1025) $PN 1
J 0
(-2538 1037);
DISPLAY 0.617021 (-2538 1037);
PAINT ORANGE (-2538 1037);
FORCEPROP 1 LAST TOLERANCE 1.0%
J 0
(-2625 975);
DISPLAY 0.617021 (-2625 975);
PAINT SKYBLUE (-2625 975);
FORCEPROP 1 LAST VALUE 240
J 2
(-2650 975);
DISPLAY 0.617021 (-2650 975);
PAINT SKYBLUE (-2650 975);
FORCEPROP 1 LAST LOCATION R3D25
J 0
(-2675 1025);
DISPLAY 0.617021 (-2675 1025);
PAINT AQUA (-2675 1025);
FORCEPROP 1 LAST PART_NUMBER G21796-294
J 0
(-2325 1025);
DISPLAY 0.617021 (-2325 1025);
PAINT BLUE (-2325 1025);
FORCEPROP 2 LAST ROOM PROC_SIDEBAND
J 0
(-2100 1125);
PAINT MONO (-2100 1125);
DISPLAY INVISIBLE (-2100 1125);
FORCEPROP 2 LAST SEC_TYPE 0402
J 0
(-2500 1225);
DISPLAY 1.021277 (-2500 1225);
PAINT ORANGE (-2500 1225);
DISPLAY INVISIBLE (-2500 1225);
FORCEPROP 2 LAST SEC 1
J 0
(-2500 1225);
DISPLAY 0.680851 (-2500 1225);
PAINT MONO (-2500 1225);
DISPLAY INVISIBLE (-2500 1225);
FORCEPROP 1 LAST PATH I66
J 0
(-2500 1175);
DISPLAY 0.978723 (-2500 1175);
PAINT WHITE (-2500 1175);
DISPLAY INVISIBLE (-2500 1175);
FORCEPROP 2 LAST BOM_COST PROC
J 0
(-2450 1025);
PAINT MONO (-2450 1025);
DISPLAY INVISIBLE (-2450 1025);
FORCEPROP 2 LAST CDS_LIB mstr_discrete
J 0
(-2450 1025);
PAINT ORANGE (-2450 1025);
DISPLAY INVISIBLE (-2450 1025);
FORCEPROP 2 LAST CDS_LOCATION R3D25
J 0
(-2700 1050);
DISPLAY 0.617021 (-2700 1050);
PAINT AQUA (-2700 1050);
DISPLAY INVISIBLE (-2700 1050);
FORCEADD RES..1
(-575 3000);
FORCEPROP 1 LAST VALUE 240
J 2
(-775 2950);
DISPLAY 0.617021 (-775 2950);
PAINT SKYBLUE (-775 2950);
FORCEPROP 1 LAST LOCATION R4P6
J 0
(-800 3000);
DISPLAY 0.617021 (-800 3000);
PAINT AQUA (-800 3000);
FORCEPROP 1 LAST PART_NUMBER G21796-294
J 0
(-425 3000);
DISPLAY 0.617021 (-425 3000);
PAINT BLUE (-425 3000);
FORCEPROP 1 LAST TOLERANCE 1.0%
J 0
(-750 2950);
DISPLAY 0.617021 (-750 2950);
PAINT SKYBLUE (-750 2950);
FORCEPROP 1 LASTPIN (-675 3000) $PN 1
J 0
(-663 3012);
DISPLAY 0.617021 (-663 3012);
PAINT ORANGE (-663 3012);
FORCEPROP 1 LASTPIN (-475 3000) $PN 2
J 0
(-513 3012);
DISPLAY 0.617021 (-513 3012);
PAINT ORANGE (-513 3012);
FORCEPROP 1 LAST WATTAGE 1/16W
J 2
(-525 2950);
DISPLAY 0.617021 (-525 2950);
PAINT SKYBLUE (-525 2950);
FORCEPROP 1 LAST PACK_TYPE 0402
J 0
(-500 2950);
DISPLAY 0.617021 (-500 2950);
PAINT SKYBLUE (-500 2950);
FORCEPROP 1 LAST MATERIAL EMPTY
J 0
(-375 2950);
DISPLAY 0.617021 (-375 2950);
PAINT RED (-375 2950);
FORCEPROP 1 LAST PATH I68
J 0
(-625 3150);
DISPLAY 0.978723 (-625 3150);
PAINT WHITE (-625 3150);
DISPLAY INVISIBLE (-625 3150);
FORCEPROP 2 LAST CDS_LOCATION R4P6
J 0
(-850 3025);
DISPLAY 0.617021 (-850 3025);
PAINT AQUA (-850 3025);
DISPLAY INVISIBLE (-850 3025);
FORCEPROP 2 LAST BOM_COST PROC
J 0
(-575 3000);
PAINT MONO (-575 3000);
DISPLAY INVISIBLE (-575 3000);
FORCEPROP 2 LAST CDS_LIB mstr_discrete
J 0
(-575 3000);
PAINT ORANGE (-575 3000);
DISPLAY INVISIBLE (-575 3000);
FORCEPROP 2 LAST SEC_TYPE 0402
J 0
(-625 3200);
DISPLAY 1.021277 (-625 3200);
PAINT ORANGE (-625 3200);
DISPLAY INVISIBLE (-625 3200);
FORCEPROP 2 LAST SEC 1
J 0
(-625 3200);
DISPLAY 0.680851 (-625 3200);
PAINT MONO (-625 3200);
DISPLAY INVISIBLE (-625 3200);
FORCEPROP 0 LAST ROOM PROC_SIDEBAND
J 0
(-200 3150);
DISPLAY 1.021277 (-200 3150);
PAINT ORANGE (-200 3150);
DISPLAY INVISIBLE (-200 3150);
FORCEADD OFFPAGE..2
(475 3000);
FORCEPROP 2 LAST $XR0 22 
J 0
(664 3000);
DISPLAY 0.638298 (664 3000);
PAINT MONO (664 3000);
FORCEPROP 2 LAST PATH I69
J 0
(650 3075);
DISPLAY 1.021277 (650 3075);
PAINT ORANGE (650 3075);
DISPLAY INVISIBLE (650 3075);
FORCEPROP 1 LAST OFFPAGE TRUE
J 0
(800 2875);
PAINT GREEN (800 2875);
DISPLAY INVISIBLE (800 2875);
FORCEPROP 2 LAST CDS_LIB mstr_standard
J 0
(475 3000);
PAINT ORANGE (475 3000);
DISPLAY INVISIBLE (475 3000);
FORCEPROP 1 LAST COMMENT_BODY TRUE
J 0
(430 2905);
DISPLAY 1.170213 (430 2905);
PAINT GREEN (430 2905);
DISPLAY INVISIBLE (430 2905);
FORCEADD OFFPAGE..2
(-1300 4200);
FORCEPROP 2 LAST $XR1 21 
J 0
(-991 4200);
DISPLAY 0.638298 (-991 4200);
PAINT MONO (-991 4200);
FORCEPROP 2 LAST $XR0 156 
J 0
(-1111 4200);
DISPLAY 0.638298 (-1111 4200);
PAINT MONO (-1111 4200);
FORCEPROP 2 LAST PATH I7
J 0
(-1100 4250);
DISPLAY 1.021277 (-1100 4250);
PAINT ORANGE (-1100 4250);
DISPLAY INVISIBLE (-1100 4250);
FORCEPROP 1 LAST COMMENT_BODY TRUE
J 0
(-1345 4105);
DISPLAY 1.170213 (-1345 4105);
PAINT GREEN (-1345 4105);
DISPLAY INVISIBLE (-1345 4105);
FORCEPROP 2 LAST CDS_LIB mstr_standard
J 0
(-1300 4200);
PAINT ORANGE (-1300 4200);
DISPLAY INVISIBLE (-1300 4200);
FORCEPROP 1 LAST OFFPAGE TRUE
J 0
(-975 4075);
PAINT GREEN (-975 4075);
DISPLAY INVISIBLE (-975 4075);
FORCEADD OFFPAGE..2
(675 850);
FORCEPROP 2 LAST $XR0 56 
J 0
(864 850);
DISPLAY 0.638298 (864 850);
PAINT MONO (864 850);
FORCEPROP 2 LAST PATH I71
J 0
(850 925);
DISPLAY 1.021277 (850 925);
PAINT ORANGE (850 925);
DISPLAY INVISIBLE (850 925);
FORCEPROP 1 LAST OFFPAGE TRUE
J 0
(1000 725);
PAINT GREEN (1000 725);
DISPLAY INVISIBLE (1000 725);
FORCEPROP 2 LAST CDS_LIB mstr_standard
J 0
(675 850);
PAINT ORANGE (675 850);
DISPLAY INVISIBLE (675 850);
FORCEPROP 1 LAST COMMENT_BODY TRUE
J 0
(630 755);
DISPLAY 1.170213 (630 755);
PAINT GREEN (630 755);
DISPLAY INVISIBLE (630 755);
FORCEADD RES..1
(-575 2800);
FORCEPROP 1 LAST TOLERANCE 1.0%
J 0
(-750 2750);
DISPLAY 0.617021 (-750 2750);
PAINT SKYBLUE (-750 2750);
FORCEPROP 1 LAST WATTAGE 1/16W
J 2
(-525 2750);
DISPLAY 0.617021 (-525 2750);
PAINT SKYBLUE (-525 2750);
FORCEPROP 1 LASTPIN (-675 2800) $PN 1
J 0
(-663 2812);
DISPLAY 0.617021 (-663 2812);
PAINT ORANGE (-663 2812);
FORCEPROP 1 LASTPIN (-475 2800) $PN 2
J 0
(-513 2812);
DISPLAY 0.617021 (-513 2812);
PAINT ORANGE (-513 2812);
FORCEPROP 1 LAST MATERIAL EMPTY
J 0
(-375 2750);
DISPLAY 0.617021 (-375 2750);
PAINT RED (-375 2750);
FORCEPROP 1 LAST PART_NUMBER G21796-294
J 0
(-425 2800);
DISPLAY 0.617021 (-425 2800);
PAINT BLUE (-425 2800);
FORCEPROP 1 LAST LOCATION R4P7
J 0
(-800 2800);
DISPLAY 0.617021 (-800 2800);
PAINT AQUA (-800 2800);
FORCEPROP 1 LAST VALUE 240
J 2
(-775 2750);
DISPLAY 0.617021 (-775 2750);
PAINT SKYBLUE (-775 2750);
FORCEPROP 1 LAST PACK_TYPE 0402
J 0
(-500 2750);
DISPLAY 0.617021 (-500 2750);
PAINT SKYBLUE (-500 2750);
FORCEPROP 2 LAST CDS_LOCATION R4P7
J 0
(-850 2825);
DISPLAY 0.617021 (-850 2825);
PAINT AQUA (-850 2825);
DISPLAY INVISIBLE (-850 2825);
FORCEPROP 2 LAST CDS_LIB mstr_discrete
J 0
(-575 2800);
PAINT ORANGE (-575 2800);
DISPLAY INVISIBLE (-575 2800);
FORCEPROP 2 LAST BOM_COST PROC
J 0
(-575 2800);
PAINT MONO (-575 2800);
DISPLAY INVISIBLE (-575 2800);
FORCEPROP 2 LAST SEC 1
J 0
(-625 3000);
DISPLAY 0.680851 (-625 3000);
PAINT MONO (-625 3000);
DISPLAY INVISIBLE (-625 3000);
FORCEPROP 2 LAST SEC_TYPE 0402
J 0
(-625 3000);
DISPLAY 1.021277 (-625 3000);
PAINT ORANGE (-625 3000);
DISPLAY INVISIBLE (-625 3000);
FORCEPROP 1 LAST PATH I72
J 0
(-625 2950);
DISPLAY 0.978723 (-625 2950);
PAINT WHITE (-625 2950);
DISPLAY INVISIBLE (-625 2950);
FORCEPROP 0 LAST ROOM PROC_SIDEBAND
J 0
(-200 2950);
DISPLAY 1.021277 (-200 2950);
PAINT ORANGE (-200 2950);
DISPLAY INVISIBLE (-200 2950);
FORCEADD OFFPAGE..2
(475 2800);
FORCEPROP 2 LAST $XR0 21 
J 0
(664 2800);
DISPLAY 0.638298 (664 2800);
PAINT MONO (664 2800);
FORCEPROP 1 LAST OFFPAGE TRUE
J 0
(800 2675);
PAINT GREEN (800 2675);
DISPLAY INVISIBLE (800 2675);
FORCEPROP 2 LAST PATH I73
J 0
(650 2875);
DISPLAY 1.021277 (650 2875);
PAINT ORANGE (650 2875);
DISPLAY INVISIBLE (650 2875);
FORCEPROP 2 LAST CDS_LIB mstr_standard
J 0
(475 2800);
PAINT ORANGE (475 2800);
DISPLAY INVISIBLE (475 2800);
FORCEPROP 1 LAST COMMENT_BODY TRUE
J 0
(430 2705);
DISPLAY 1.170213 (430 2705);
PAINT GREEN (430 2705);
DISPLAY INVISIBLE (430 2705);
FORCEADD RES..1
(-425 650);
FORCEPROP 1 LAST LOCATION R7P15
J 0
(-650 650);
DISPLAY 0.617021 (-650 650);
PAINT AQUA (-650 650);
FORCEPROP 1 LAST TOLERANCE 1.0%
J 0
(-600 600);
DISPLAY 0.617021 (-600 600);
PAINT SKYBLUE (-600 600);
FORCEPROP 1 LASTPIN (-525 650) $PN 1
J 0
(-513 662);
DISPLAY 0.617021 (-513 662);
PAINT ORANGE (-513 662);
FORCEPROP 1 LASTPIN (-325 650) $PN 2
J 0
(-363 662);
DISPLAY 0.617021 (-363 662);
PAINT ORANGE (-363 662);
FORCEPROP 1 LAST VALUE 240
J 2
(-625 600);
DISPLAY 0.617021 (-625 600);
PAINT SKYBLUE (-625 600);
FORCEPROP 1 LAST WATTAGE 1/16W
J 2
(-375 600);
DISPLAY 0.617021 (-375 600);
PAINT SKYBLUE (-375 600);
FORCEPROP 1 LAST PACK_TYPE 0402
J 0
(-350 600);
DISPLAY 0.617021 (-350 600);
PAINT SKYBLUE (-350 600);
FORCEPROP 1 LAST PART_NUMBER G21796-294
J 0
(-300 650);
DISPLAY 0.617021 (-300 650);
PAINT BLUE (-300 650);
FORCEPROP 1 LAST MATERIAL EMPTY
J 0
(-225 600);
DISPLAY 0.617021 (-225 600);
PAINT RED (-225 600);
FORCEPROP 1 LAST PATH I74
J 0
(-475 800);
DISPLAY 0.978723 (-475 800);
PAINT WHITE (-475 800);
DISPLAY INVISIBLE (-475 800);
FORCEPROP 0 LAST ROOM PROC_SIDEBAND
J 0
(-50 800);
DISPLAY 1.021277 (-50 800);
PAINT ORANGE (-50 800);
DISPLAY INVISIBLE (-50 800);
FORCEPROP 2 LAST SEC_TYPE 0402
J 0
(-475 850);
DISPLAY 1.021277 (-475 850);
PAINT ORANGE (-475 850);
DISPLAY INVISIBLE (-475 850);
FORCEPROP 2 LAST SEC 1
J 0
(-475 850);
DISPLAY 0.680851 (-475 850);
PAINT MONO (-475 850);
DISPLAY INVISIBLE (-475 850);
FORCEPROP 2 LAST BOM_COST PROC
J 0
(-425 650);
PAINT MONO (-425 650);
DISPLAY INVISIBLE (-425 650);
FORCEPROP 2 LAST CDS_LIB mstr_discrete
J 0
(-425 650);
PAINT ORANGE (-425 650);
DISPLAY INVISIBLE (-425 650);
FORCEPROP 2 LAST CDS_LOCATION R7P15
J 0
(-725 675);
DISPLAY 0.617021 (-725 675);
PAINT AQUA (-725 675);
DISPLAY INVISIBLE (-725 675);
FORCEADD OFFPAGE..2
(675 650);
FORCEPROP 2 LAST $XR0 55 
J 0
(864 650);
DISPLAY 0.638298 (864 650);
PAINT MONO (864 650);
FORCEPROP 1 LAST OFFPAGE TRUE
J 0
(1000 525);
PAINT GREEN (1000 525);
DISPLAY INVISIBLE (1000 525);
FORCEPROP 2 LAST PATH I75
J 0
(850 725);
DISPLAY 1.021277 (850 725);
PAINT ORANGE (850 725);
DISPLAY INVISIBLE (850 725);
FORCEPROP 2 LAST CDS_LIB mstr_standard
J 0
(675 650);
PAINT ORANGE (675 650);
DISPLAY INVISIBLE (675 650);
FORCEPROP 1 LAST COMMENT_BODY TRUE
J 0
(630 555);
DISPLAY 1.170213 (630 555);
PAINT GREEN (630 555);
DISPLAY INVISIBLE (630 555);
FORCEADD RES..1
(-2450 800);
FORCEPROP 1 LASTPIN (-2350 800) $PN 2
J 0
(-2388 812);
DISPLAY 0.617021 (-2388 812);
PAINT ORANGE (-2388 812);
FORCEPROP 1 LASTPIN (-2550 800) $PN 1
J 0
(-2538 812);
DISPLAY 0.617021 (-2538 812);
PAINT ORANGE (-2538 812);
FORCEPROP 1 LAST PACK_TYPE 0402
J 0
(-2375 750);
DISPLAY 0.617021 (-2375 750);
PAINT SKYBLUE (-2375 750);
FORCEPROP 1 LAST MATERIAL EMPTY
J 0
(-2250 750);
DISPLAY 0.617021 (-2250 750);
PAINT RED (-2250 750);
FORCEPROP 1 LAST WATTAGE 1/16W
J 2
(-2400 750);
DISPLAY 0.617021 (-2400 750);
PAINT SKYBLUE (-2400 750);
FORCEPROP 1 LAST LOCATION R7P22
J 0
(-2675 800);
DISPLAY 0.617021 (-2675 800);
PAINT AQUA (-2675 800);
FORCEPROP 1 LAST VALUE 240
J 2
(-2650 750);
DISPLAY 0.617021 (-2650 750);
PAINT SKYBLUE (-2650 750);
FORCEPROP 1 LAST TOLERANCE 1.0%
J 0
(-2625 750);
DISPLAY 0.617021 (-2625 750);
PAINT SKYBLUE (-2625 750);
FORCEPROP 1 LAST PART_NUMBER G21796-294
J 0
(-2325 800);
DISPLAY 0.617021 (-2325 800);
PAINT BLUE (-2325 800);
FORCEPROP 2 LAST SEC 1
J 0
(-2500 1000);
DISPLAY 0.680851 (-2500 1000);
PAINT MONO (-2500 1000);
DISPLAY INVISIBLE (-2500 1000);
FORCEPROP 2 LAST SEC_TYPE 0402
J 0
(-2500 1000);
DISPLAY 1.021277 (-2500 1000);
PAINT ORANGE (-2500 1000);
DISPLAY INVISIBLE (-2500 1000);
FORCEPROP 0 LAST ROOM PROC_SIDEBAND
J 0
(-2500 950);
DISPLAY 1.021277 (-2500 950);
PAINT ORANGE (-2500 950);
DISPLAY INVISIBLE (-2500 950);
FORCEPROP 1 LAST PATH I76
J 0
(-2500 950);
DISPLAY 0.978723 (-2500 950);
PAINT WHITE (-2500 950);
DISPLAY INVISIBLE (-2500 950);
FORCEPROP 0 LAST BOM_COST PROC
J 0
(-2500 950);
DISPLAY 1.021277 (-2500 950);
PAINT ORANGE (-2500 950);
DISPLAY INVISIBLE (-2500 950);
FORCEPROP 2 LAST CDS_LIB mstr_discrete
J 0
(-2450 800);
PAINT ORANGE (-2450 800);
DISPLAY INVISIBLE (-2450 800);
FORCEPROP 2 LAST CDS_LOCATION R7P22
J 0
(-2725 825);
DISPLAY 0.617021 (-2725 825);
PAINT AQUA (-2725 825);
DISPLAY INVISIBLE (-2725 825);
FORCEADD OFFPAGE..2
(-1325 800);
FORCEPROP 2 LAST $XR0 55 
J 0
(-1136 800);
DISPLAY 0.638298 (-1136 800);
PAINT MONO (-1136 800);
FORCEPROP 1 LAST OFFPAGE TRUE
J 0
(-1000 675);
PAINT GREEN (-1000 675);
DISPLAY INVISIBLE (-1000 675);
FORCEPROP 2 LAST PATH I77
J 0
(-1150 875);
DISPLAY 1.021277 (-1150 875);
PAINT ORANGE (-1150 875);
DISPLAY INVISIBLE (-1150 875);
FORCEPROP 2 LAST CDS_LIB mstr_standard
J 0
(-1325 800);
PAINT ORANGE (-1325 800);
DISPLAY INVISIBLE (-1325 800);
FORCEPROP 1 LAST COMMENT_BODY TRUE
J 0
(-1370 705);
DISPLAY 1.170213 (-1370 705);
PAINT GREEN (-1370 705);
DISPLAY INVISIBLE (-1370 705);
FORCEADD GND..1
(-1225 2725);
FORCEPROP 3 LASTPIN (-1225 2775) SIG_NAME GND\g
J 0
(-1215 2785);
DISPLAY 0.659574 (-1215 2785);
PAINT MONO (-1215 2785);
DISPLAY INVISIBLE (-1215 2785);
FORCEPROP 1 LAST PATH I78
J 0
(-1150 2725);
DISPLAY 0.872340 (-1150 2725);
PAINT AQUA (-1150 2725);
DISPLAY INVISIBLE (-1150 2725);
FORCEPROP 1 LAST SIZE 1B
J 0
(-1150 2675);
DISPLAY 1.170213 (-1150 2675);
PAINT GREEN (-1150 2675);
DISPLAY INVISIBLE (-1150 2675);
FORCEPROP 2 LAST CDS_LIB mstr_symbols
J 0
(-1225 2725);
PAINT ORANGE (-1225 2725);
DISPLAY INVISIBLE (-1225 2725);
FORCEPROP 1 LAST VOLTAGE 0.0V
J 0
(-1270 2682);
DISPLAY 0.340426 (-1270 2682);
PAINT SKYBLUE (-1270 2682);
DISPLAY INVISIBLE (-1270 2682);
FORCEPROP 1 LAST BODY_TYPE PLUMBING
J 0
(-1270 2682);
DISPLAY 0.340426 (-1270 2682);
PAINT GREEN (-1270 2682);
DISPLAY INVISIBLE (-1270 2682);
FORCEPROP 1 LAST HDL_POWER GND
J 0
(-1225 2875);
DISPLAY 0.702128 (-1225 2875);
PAINT GREEN (-1225 2875);
DISPLAY INVISIBLE (-1225 2875);
FORCEADD RES..1
(-1575 3200);
FORCEPROP 1 LAST PART_NUMBER G21796-047
J 0
(-1450 3150);
DISPLAY 0.617021 (-1450 3150);
PAINT BLUE (-1450 3150);
FORCEPROP 1 LASTPIN (-1475 3200) $PN 2
J 0
(-1513 3212);
DISPLAY 0.617021 (-1513 3212);
PAINT ORANGE (-1513 3212);
FORCEPROP 1 LAST TOLERANCE 1%
J 0
(-1550 3150);
DISPLAY 0.617021 (-1550 3150);
PAINT SKYBLUE (-1550 3150);
FORCEPROP 1 LAST PACK_TYPE 0402
J 0
(-2150 3150);
DISPLAY 0.617021 (-2150 3150);
PAINT SKYBLUE (-2150 3150);
FORCEPROP 1 LAST MATERIAL CHIP
J 0
(-2000 3150);
DISPLAY 0.617021 (-2000 3150);
PAINT SKYBLUE (-2000 3150);
FORCEPROP 1 LAST LOCATION R5P2
J 0
(-1625 3250);
DISPLAY 0.617021 (-1625 3250);
PAINT AQUA (-1625 3250);
FORCEPROP 1 LASTPIN (-1675 3200) $PN 1
J 0
(-1663 3212);
DISPLAY 0.617021 (-1663 3212);
PAINT ORANGE (-1663 3212);
FORCEPROP 1 LAST VALUE 49.9
J 2
(-1625 3150);
DISPLAY 0.617021 (-1625 3150);
PAINT SKYBLUE (-1625 3150);
FORCEPROP 1 LAST WATTAGE 1/16W
J 2
(-1750 3150);
DISPLAY 0.617021 (-1750 3150);
PAINT SKYBLUE (-1750 3150);
FORCEPROP 0 LAST ROOM CPU0
J 0
(-1625 3350);
DISPLAY 1.021277 (-1625 3350);
PAINT ORANGE (-1625 3350);
DISPLAY INVISIBLE (-1625 3350);
FORCEPROP 1 LAST PATH I79
J 0
(-1625 3350);
DISPLAY 0.978723 (-1625 3350);
PAINT WHITE (-1625 3350);
DISPLAY INVISIBLE (-1625 3350);
FORCEPROP 2 LAST SEC 1
J 0
(-1625 3400);
DISPLAY 0.680851 (-1625 3400);
PAINT MONO (-1625 3400);
DISPLAY INVISIBLE (-1625 3400);
FORCEPROP 2 LAST SEC_TYPE 0402
J 0
(-1625 3400);
DISPLAY 1.021277 (-1625 3400);
PAINT ORANGE (-1625 3400);
DISPLAY INVISIBLE (-1625 3400);
FORCEPROP 2 LAST CDS_LOCATION R5P2
J 0
(-1625 3250);
DISPLAY 0.617021 (-1625 3250);
PAINT AQUA (-1625 3250);
DISPLAY INVISIBLE (-1625 3250);
FORCEPROP 2 LAST CDS_LIB mstr_discrete
J 0
(-1575 3200);
PAINT ORANGE (-1575 3200);
DISPLAY INVISIBLE (-1575 3200);
FORCEADD OFFPAGE..2
(-1300 4000);
FORCEPROP 2 LAST $XR0 21 
J 0
(-1111 4000);
DISPLAY 0.638298 (-1111 4000);
PAINT MONO (-1111 4000);
FORCEPROP 1 LAST OFFPAGE TRUE
J 0
(-975 3875);
PAINT GREEN (-975 3875);
DISPLAY INVISIBLE (-975 3875);
FORCEPROP 2 LAST PATH I8
J 0
(-1100 4050);
DISPLAY 1.021277 (-1100 4050);
PAINT ORANGE (-1100 4050);
DISPLAY INVISIBLE (-1100 4050);
FORCEPROP 2 LAST CDS_LIB mstr_standard
J 0
(-1300 4000);
PAINT ORANGE (-1300 4000);
DISPLAY INVISIBLE (-1300 4000);
FORCEPROP 1 LAST COMMENT_BODY TRUE
J 0
(-1345 3905);
DISPLAY 1.170213 (-1345 3905);
PAINT GREEN (-1345 3905);
DISPLAY INVISIBLE (-1345 3905);
FORCEADD RES..1
(-1575 3075);
FORCEPROP 1 LASTPIN (-1475 3075) $PN 2
J 0
(-1513 3087);
DISPLAY 0.617021 (-1513 3087);
PAINT ORANGE (-1513 3087);
FORCEPROP 1 LAST LOCATION R5P3
J 0
(-1625 3125);
DISPLAY 0.617021 (-1625 3125);
PAINT AQUA (-1625 3125);
FORCEPROP 1 LASTPIN (-1675 3075) $PN 1
J 0
(-1663 3087);
DISPLAY 0.617021 (-1663 3087);
PAINT ORANGE (-1663 3087);
FORCEPROP 1 LAST PACK_TYPE 0402
J 0
(-2150 3025);
DISPLAY 0.617021 (-2150 3025);
PAINT SKYBLUE (-2150 3025);
FORCEPROP 1 LAST MATERIAL CHIP
J 0
(-2000 3025);
DISPLAY 0.617021 (-2000 3025);
PAINT SKYBLUE (-2000 3025);
FORCEPROP 1 LAST TOLERANCE 1%
J 0
(-1550 3025);
DISPLAY 0.617021 (-1550 3025);
PAINT SKYBLUE (-1550 3025);
FORCEPROP 1 LAST VALUE 49.9
J 2
(-1625 3025);
DISPLAY 0.617021 (-1625 3025);
PAINT SKYBLUE (-1625 3025);
FORCEPROP 1 LAST PART_NUMBER G21796-047
J 0
(-1450 3025);
DISPLAY 0.617021 (-1450 3025);
PAINT BLUE (-1450 3025);
FORCEPROP 1 LAST WATTAGE 1/16W
J 2
(-1750 3025);
DISPLAY 0.617021 (-1750 3025);
PAINT SKYBLUE (-1750 3025);
FORCEPROP 0 LAST ROOM CPU0
J 0
(-1625 3225);
DISPLAY 1.021277 (-1625 3225);
PAINT ORANGE (-1625 3225);
DISPLAY INVISIBLE (-1625 3225);
FORCEPROP 1 LAST PATH I80
J 0
(-1625 3225);
DISPLAY 0.978723 (-1625 3225);
PAINT WHITE (-1625 3225);
DISPLAY INVISIBLE (-1625 3225);
FORCEPROP 2 LAST SEC_TYPE 0402
J 0
(-1625 3275);
DISPLAY 1.021277 (-1625 3275);
PAINT ORANGE (-1625 3275);
DISPLAY INVISIBLE (-1625 3275);
FORCEPROP 2 LAST SEC 1
J 0
(-1625 3275);
DISPLAY 0.680851 (-1625 3275);
PAINT MONO (-1625 3275);
DISPLAY INVISIBLE (-1625 3275);
FORCEPROP 2 LAST CDS_LOCATION R5P3
J 0
(-1625 3125);
DISPLAY 0.617021 (-1625 3125);
PAINT AQUA (-1625 3125);
DISPLAY INVISIBLE (-1625 3125);
FORCEPROP 2 LAST CDS_LIB mstr_discrete
J 0
(-1575 3075);
PAINT ORANGE (-1575 3075);
DISPLAY INVISIBLE (-1575 3075);
FORCEADD RES..1
(-1575 2925);
FORCEPROP 1 LAST TOLERANCE 1%
J 0
(-1550 2875);
DISPLAY 0.617021 (-1550 2875);
PAINT SKYBLUE (-1550 2875);
FORCEPROP 1 LAST VALUE 49.9
J 2
(-1625 2875);
DISPLAY 0.617021 (-1625 2875);
PAINT SKYBLUE (-1625 2875);
FORCEPROP 1 LAST PACK_TYPE 0402
J 0
(-2150 2875);
DISPLAY 0.617021 (-2150 2875);
PAINT SKYBLUE (-2150 2875);
FORCEPROP 1 LAST MATERIAL CHIP
J 0
(-2000 2875);
DISPLAY 0.617021 (-2000 2875);
PAINT SKYBLUE (-2000 2875);
FORCEPROP 1 LASTPIN (-1675 2925) $PN 1
J 0
(-1663 2937);
DISPLAY 0.617021 (-1663 2937);
PAINT ORANGE (-1663 2937);
FORCEPROP 1 LAST LOCATION R6D5
J 0
(-1625 2975);
DISPLAY 0.617021 (-1625 2975);
PAINT AQUA (-1625 2975);
FORCEPROP 1 LASTPIN (-1475 2925) $PN 2
J 0
(-1513 2937);
DISPLAY 0.617021 (-1513 2937);
PAINT ORANGE (-1513 2937);
FORCEPROP 1 LAST PART_NUMBER G21796-047
J 0
(-1450 2875);
DISPLAY 0.617021 (-1450 2875);
PAINT BLUE (-1450 2875);
FORCEPROP 1 LAST WATTAGE 1/16W
J 2
(-1750 2875);
DISPLAY 0.617021 (-1750 2875);
PAINT SKYBLUE (-1750 2875);
FORCEPROP 2 LAST SEC_TYPE 0402
J 0
(-1625 3125);
DISPLAY 1.021277 (-1625 3125);
PAINT ORANGE (-1625 3125);
DISPLAY INVISIBLE (-1625 3125);
FORCEPROP 2 LAST SEC 1
J 0
(-1625 3125);
DISPLAY 0.680851 (-1625 3125);
PAINT MONO (-1625 3125);
DISPLAY INVISIBLE (-1625 3125);
FORCEPROP 1 LAST PATH I81
J 0
(-1625 3075);
DISPLAY 0.978723 (-1625 3075);
PAINT WHITE (-1625 3075);
DISPLAY INVISIBLE (-1625 3075);
FORCEPROP 0 LAST ROOM CPU0
J 0
(-1625 3075);
DISPLAY 1.021277 (-1625 3075);
PAINT ORANGE (-1625 3075);
DISPLAY INVISIBLE (-1625 3075);
FORCEPROP 2 LAST CDS_LOCATION R6D5
J 0
(-1625 2975);
DISPLAY 0.617021 (-1625 2975);
PAINT AQUA (-1625 2975);
DISPLAY INVISIBLE (-1625 2975);
FORCEPROP 2 LAST CDS_LIB mstr_discrete
J 0
(-1575 2925);
PAINT ORANGE (-1575 2925);
DISPLAY INVISIBLE (-1575 2925);
FORCEADD OFFPAGE..2
R 2
(-2800 3200);
FORCEPROP 2 LAST $XR0 21 
J 0
(-3024 3200);
DISPLAY 0.638298 (-3024 3200);
PAINT MONO (-3024 3200);
FORCEPROP 1 LAST COMMENT_BODY TRUE
J 2
(-2755 3105);
DISPLAY 1.170213 (-2755 3105);
PAINT GREEN (-2755 3105);
DISPLAY INVISIBLE (-2755 3105);
FORCEPROP 2 LAST CDS_LIB mstr_standard
J 2
(-2800 3200);
PAINT ORANGE (-2800 3200);
DISPLAY INVISIBLE (-2800 3200);
FORCEPROP 2 LAST PATH I82
J 2
(-2975 3275);
DISPLAY 1.021277 (-2975 3275);
PAINT ORANGE (-2975 3275);
DISPLAY INVISIBLE (-2975 3275);
FORCEPROP 1 LAST OFFPAGE TRUE
J 2
(-3125 3075);
PAINT GREEN (-3125 3075);
DISPLAY INVISIBLE (-3125 3075);
FORCEADD OFFPAGE..2
R 2
(-2800 3075);
FORCEPROP 2 LAST $XR0 21 
J 0
(-3024 3075);
DISPLAY 0.638298 (-3024 3075);
PAINT MONO (-3024 3075);
FORCEPROP 2 LAST PATH I83
J 0
(-2750 3150);
DISPLAY 1.021277 (-2750 3150);
PAINT ORANGE (-2750 3150);
DISPLAY INVISIBLE (-2750 3150);
FORCEPROP 2 LAST CDS_LIB mstr_standard
J 0
(-2800 3075);
PAINT ORANGE (-2800 3075);
DISPLAY INVISIBLE (-2800 3075);
FORCEPROP 1 LAST COMMENT_BODY TRUE
J 2
(-2755 2980);
DISPLAY 1.170213 (-2755 2980);
PAINT GREEN (-2755 2980);
DISPLAY INVISIBLE (-2755 2980);
FORCEPROP 1 LAST OFFPAGE TRUE
J 2
(-3125 2950);
PAINT GREEN (-3125 2950);
DISPLAY INVISIBLE (-3125 2950);
FORCEADD OFFPAGE..2
R 2
(-2800 2925);
FORCEPROP 2 LAST $XR0 21 
J 0
(-3024 2925);
DISPLAY 0.638298 (-3024 2925);
PAINT MONO (-3024 2925);
FORCEPROP 2 LAST CDS_LIB mstr_standard
J 0
(-2800 2925);
PAINT ORANGE (-2800 2925);
DISPLAY INVISIBLE (-2800 2925);
FORCEPROP 1 LAST COMMENT_BODY TRUE
J 2
(-2755 2830);
DISPLAY 1.170213 (-2755 2830);
PAINT GREEN (-2755 2830);
DISPLAY INVISIBLE (-2755 2830);
FORCEPROP 2 LAST PATH I84
J 0
(-2750 3000);
DISPLAY 1.021277 (-2750 3000);
PAINT ORANGE (-2750 3000);
DISPLAY INVISIBLE (-2750 3000);
FORCEPROP 1 LAST OFFPAGE TRUE
J 2
(-3125 2800);
PAINT GREEN (-3125 2800);
DISPLAY INVISIBLE (-3125 2800);
FORCEADD RES..1
(325 2475);
FORCEPROP 1 LAST MATERIAL CHIP
J 0
(-100 2425);
DISPLAY 0.617021 (-100 2425);
PAINT SKYBLUE (-100 2425);
FORCEPROP 1 LAST PACK_TYPE 0402
J 0
(-250 2425);
DISPLAY 0.617021 (-250 2425);
PAINT SKYBLUE (-250 2425);
FORCEPROP 1 LASTPIN (225 2475) $PN 1
J 0
(237 2487);
DISPLAY 0.617021 (237 2487);
PAINT ORANGE (237 2487);
FORCEPROP 1 LAST VALUE 49.9
J 2
(275 2425);
DISPLAY 0.617021 (275 2425);
PAINT SKYBLUE (275 2425);
FORCEPROP 1 LAST TOLERANCE 1%
J 0
(350 2425);
DISPLAY 0.617021 (350 2425);
PAINT SKYBLUE (350 2425);
FORCEPROP 1 LASTPIN (425 2475) $PN 2
J 0
(387 2487);
DISPLAY 0.617021 (387 2487);
PAINT ORANGE (387 2487);
FORCEPROP 1 LAST PART_NUMBER G21796-047
J 0
(450 2425);
DISPLAY 0.617021 (450 2425);
PAINT BLUE (450 2425);
FORCEPROP 1 LAST LOCATION R8P1
J 0
(275 2525);
DISPLAY 0.617021 (275 2525);
PAINT AQUA (275 2525);
FORCEPROP 1 LAST WATTAGE 1/16W
J 2
(150 2425);
DISPLAY 0.617021 (150 2425);
PAINT SKYBLUE (150 2425);
FORCEPROP 0 LAST ROOM CPU1
J 0
(275 2625);
DISPLAY 1.021277 (275 2625);
PAINT ORANGE (275 2625);
DISPLAY INVISIBLE (275 2625);
FORCEPROP 1 LAST PATH I85
J 0
(275 2625);
DISPLAY 0.978723 (275 2625);
PAINT WHITE (275 2625);
DISPLAY INVISIBLE (275 2625);
FORCEPROP 2 LAST SEC 1
J 0
(275 2675);
DISPLAY 0.680851 (275 2675);
PAINT MONO (275 2675);
DISPLAY INVISIBLE (275 2675);
FORCEPROP 2 LAST SEC_TYPE 0402
J 0
(275 2675);
DISPLAY 1.021277 (275 2675);
PAINT ORANGE (275 2675);
DISPLAY INVISIBLE (275 2675);
FORCEPROP 2 LAST CDS_LOCATION R8P1
J 0
(275 2525);
DISPLAY 0.617021 (275 2525);
PAINT AQUA (275 2525);
DISPLAY INVISIBLE (275 2525);
FORCEPROP 2 LAST CDS_LIB mstr_discrete
J 0
(325 2475);
PAINT ORANGE (325 2475);
DISPLAY INVISIBLE (325 2475);
FORCEADD RES..1
(325 2350);
FORCEPROP 1 LASTPIN (425 2350) $PN 2
J 0
(387 2362);
DISPLAY 0.617021 (387 2362);
PAINT ORANGE (387 2362);
FORCEPROP 1 LAST TOLERANCE 1%
J 0
(350 2300);
DISPLAY 0.617021 (350 2300);
PAINT SKYBLUE (350 2300);
FORCEPROP 1 LAST PACK_TYPE 0402
J 0
(-250 2300);
DISPLAY 0.617021 (-250 2300);
PAINT SKYBLUE (-250 2300);
FORCEPROP 1 LAST PART_NUMBER G21796-047
J 0
(450 2300);
DISPLAY 0.617021 (450 2300);
PAINT BLUE (450 2300);
FORCEPROP 1 LAST MATERIAL CHIP
J 0
(-100 2300);
DISPLAY 0.617021 (-100 2300);
PAINT SKYBLUE (-100 2300);
FORCEPROP 1 LAST LOCATION R8P2
J 0
(275 2400);
DISPLAY 0.617021 (275 2400);
PAINT AQUA (275 2400);
FORCEPROP 1 LASTPIN (225 2350) $PN 1
J 0
(237 2362);
DISPLAY 0.617021 (237 2362);
PAINT ORANGE (237 2362);
FORCEPROP 1 LAST VALUE 49.9
J 2
(275 2300);
DISPLAY 0.617021 (275 2300);
PAINT SKYBLUE (275 2300);
FORCEPROP 1 LAST WATTAGE 1/16W
J 2
(150 2300);
DISPLAY 0.617021 (150 2300);
PAINT SKYBLUE (150 2300);
FORCEPROP 2 LAST SEC 1
J 0
(275 2550);
DISPLAY 0.680851 (275 2550);
PAINT MONO (275 2550);
DISPLAY INVISIBLE (275 2550);
FORCEPROP 2 LAST SEC_TYPE 0402
J 0
(275 2550);
DISPLAY 1.021277 (275 2550);
PAINT ORANGE (275 2550);
DISPLAY INVISIBLE (275 2550);
FORCEPROP 0 LAST ROOM CPU1
J 0
(275 2500);
DISPLAY 1.021277 (275 2500);
PAINT ORANGE (275 2500);
DISPLAY INVISIBLE (275 2500);
FORCEPROP 1 LAST PATH I86
J 0
(275 2500);
DISPLAY 0.978723 (275 2500);
PAINT WHITE (275 2500);
DISPLAY INVISIBLE (275 2500);
FORCEPROP 2 LAST CDS_LOCATION R8P2
J 0
(275 2400);
DISPLAY 0.617021 (275 2400);
PAINT AQUA (275 2400);
DISPLAY INVISIBLE (275 2400);
FORCEPROP 2 LAST CDS_LIB mstr_discrete
J 0
(325 2350);
PAINT ORANGE (325 2350);
DISPLAY INVISIBLE (325 2350);
FORCEADD GND..1
(675 2000);
FORCEPROP 3 LASTPIN (675 2050) SIG_NAME GND\g
J 0
(685 2060);
DISPLAY 0.659574 (685 2060);
PAINT MONO (685 2060);
DISPLAY INVISIBLE (685 2060);
FORCEPROP 1 LAST HDL_POWER GND
J 0
(675 2150);
DISPLAY 0.702128 (675 2150);
PAINT GREEN (675 2150);
DISPLAY INVISIBLE (675 2150);
FORCEPROP 1 LAST PATH I87
J 0
(750 2000);
DISPLAY 0.872340 (750 2000);
PAINT AQUA (750 2000);
DISPLAY INVISIBLE (750 2000);
FORCEPROP 1 LAST BODY_TYPE PLUMBING
J 0
(630 1957);
DISPLAY 0.340426 (630 1957);
PAINT GREEN (630 1957);
DISPLAY INVISIBLE (630 1957);
FORCEPROP 1 LAST SIZE 1B
J 0
(750 1950);
DISPLAY 1.170213 (750 1950);
PAINT GREEN (750 1950);
DISPLAY INVISIBLE (750 1950);
FORCEPROP 2 LAST CDS_LIB mstr_symbols
J 0
(675 2000);
PAINT ORANGE (675 2000);
DISPLAY INVISIBLE (675 2000);
FORCEPROP 1 LAST VOLTAGE 0.0V
J 0
(630 1957);
DISPLAY 0.340426 (630 1957);
PAINT SKYBLUE (630 1957);
DISPLAY INVISIBLE (630 1957);
FORCEADD RES..1
(325 2200);
FORCEPROP 1 LAST MATERIAL CHIP
J 0
(-100 2150);
DISPLAY 0.617021 (-100 2150);
PAINT SKYBLUE (-100 2150);
FORCEPROP 1 LAST PACK_TYPE 0402
J 0
(-250 2150);
DISPLAY 0.617021 (-250 2150);
PAINT SKYBLUE (-250 2150);
FORCEPROP 1 LAST LOCATION R3D9
J 0
(275 2250);
DISPLAY 0.617021 (275 2250);
PAINT AQUA (275 2250);
FORCEPROP 1 LAST TOLERANCE 1%
J 0
(350 2150);
DISPLAY 0.617021 (350 2150);
PAINT SKYBLUE (350 2150);
FORCEPROP 1 LASTPIN (425 2200) $PN 2
J 0
(387 2212);
DISPLAY 0.617021 (387 2212);
PAINT ORANGE (387 2212);
FORCEPROP 1 LAST PART_NUMBER G21796-047
J 0
(450 2150);
DISPLAY 0.617021 (450 2150);
PAINT BLUE (450 2150);
FORCEPROP 1 LASTPIN (225 2200) $PN 1
J 0
(237 2212);
DISPLAY 0.617021 (237 2212);
PAINT ORANGE (237 2212);
FORCEPROP 1 LAST VALUE 49.9
J 2
(275 2150);
DISPLAY 0.617021 (275 2150);
PAINT SKYBLUE (275 2150);
FORCEPROP 1 LAST WATTAGE 1/16W
J 2
(150 2150);
DISPLAY 0.617021 (150 2150);
PAINT SKYBLUE (150 2150);
FORCEPROP 2 LAST SEC_TYPE 0402
J 0
(275 2400);
DISPLAY 1.021277 (275 2400);
PAINT ORANGE (275 2400);
DISPLAY INVISIBLE (275 2400);
FORCEPROP 0 LAST ROOM CPU1
J 0
(275 2350);
DISPLAY 1.021277 (275 2350);
PAINT ORANGE (275 2350);
DISPLAY INVISIBLE (275 2350);
FORCEPROP 1 LAST PATH I88
J 0
(275 2350);
DISPLAY 0.978723 (275 2350);
PAINT WHITE (275 2350);
DISPLAY INVISIBLE (275 2350);
FORCEPROP 2 LAST SEC 1
J 0
(275 2400);
DISPLAY 0.680851 (275 2400);
PAINT MONO (275 2400);
DISPLAY INVISIBLE (275 2400);
FORCEPROP 2 LAST CDS_LOCATION R3D9
J 0
(275 2250);
DISPLAY 0.617021 (275 2250);
PAINT AQUA (275 2250);
DISPLAY INVISIBLE (275 2250);
FORCEPROP 2 LAST CDS_LIB mstr_discrete
J 0
(325 2200);
PAINT ORANGE (325 2200);
DISPLAY INVISIBLE (325 2200);
FORCEADD OFFPAGE..2
R 2
(-900 2475);
FORCEPROP 2 LAST $XR0 55 
J 0
(-1124 2475);
DISPLAY 0.638298 (-1124 2475);
PAINT MONO (-1124 2475);
FORCEPROP 2 LAST PATH I89
J 0
(-850 2550);
DISPLAY 1.021277 (-850 2550);
PAINT ORANGE (-850 2550);
DISPLAY INVISIBLE (-850 2550);
FORCEPROP 1 LAST COMMENT_BODY TRUE
J 2
(-855 2380);
DISPLAY 1.170213 (-855 2380);
PAINT GREEN (-855 2380);
DISPLAY INVISIBLE (-855 2380);
FORCEPROP 2 LAST CDS_LIB mstr_standard
J 2
(-900 2475);
PAINT ORANGE (-900 2475);
DISPLAY INVISIBLE (-900 2475);
FORCEPROP 1 LAST OFFPAGE TRUE
J 2
(-1225 2350);
PAINT GREEN (-1225 2350);
DISPLAY INVISIBLE (-1225 2350);
FORCEADD OFFPAGE..2
(550 1275);
FORCEPROP 2 LAST $XR0 55 
J 0
(739 1275);
DISPLAY 0.638298 (739 1275);
PAINT MONO (739 1275);
FORCEPROP 1 LAST OFFPAGE TRUE
J 0
(875 1150);
PAINT GREEN (875 1150);
DISPLAY INVISIBLE (875 1150);
FORCEPROP 2 LAST PATH I9
J 0
(750 1325);
DISPLAY 1.021277 (750 1325);
PAINT ORANGE (750 1325);
DISPLAY INVISIBLE (750 1325);
FORCEPROP 2 LAST CDS_LIB mstr_standard
J 0
(550 1275);
PAINT ORANGE (550 1275);
DISPLAY INVISIBLE (550 1275);
FORCEPROP 1 LAST COMMENT_BODY TRUE
J 0
(505 1180);
DISPLAY 1.170213 (505 1180);
PAINT GREEN (505 1180);
DISPLAY INVISIBLE (505 1180);
FORCEADD OFFPAGE..2
R 2
(-900 2350);
FORCEPROP 2 LAST $XR0 55 
J 0
(-1124 2350);
DISPLAY 0.638298 (-1124 2350);
PAINT MONO (-1124 2350);
FORCEPROP 2 LAST PATH I90
J 0
(-850 2425);
DISPLAY 1.021277 (-850 2425);
PAINT ORANGE (-850 2425);
DISPLAY INVISIBLE (-850 2425);
FORCEPROP 2 LAST CDS_LIB mstr_standard
J 0
(-900 2350);
PAINT ORANGE (-900 2350);
DISPLAY INVISIBLE (-900 2350);
FORCEPROP 1 LAST COMMENT_BODY TRUE
J 2
(-855 2255);
DISPLAY 1.170213 (-855 2255);
PAINT GREEN (-855 2255);
DISPLAY INVISIBLE (-855 2255);
FORCEPROP 1 LAST OFFPAGE TRUE
J 2
(-1225 2225);
PAINT GREEN (-1225 2225);
DISPLAY INVISIBLE (-1225 2225);
FORCEADD OFFPAGE..2
R 2
(-900 2200);
FORCEPROP 2 LAST $XR0 55 
J 0
(-1124 2200);
DISPLAY 0.638298 (-1124 2200);
PAINT MONO (-1124 2200);
FORCEPROP 2 LAST PATH I91
J 0
(-850 2275);
DISPLAY 1.021277 (-850 2275);
PAINT ORANGE (-850 2275);
DISPLAY INVISIBLE (-850 2275);
FORCEPROP 2 LAST CDS_LIB mstr_standard
J 0
(-900 2200);
PAINT ORANGE (-900 2200);
DISPLAY INVISIBLE (-900 2200);
FORCEPROP 1 LAST COMMENT_BODY TRUE
J 2
(-855 2105);
DISPLAY 1.170213 (-855 2105);
PAINT GREEN (-855 2105);
DISPLAY INVISIBLE (-855 2105);
FORCEPROP 1 LAST OFFPAGE TRUE
J 2
(-1225 2075);
PAINT GREEN (-1225 2075);
DISPLAY INVISIBLE (-1225 2075);
FORCEADD GND..1
(-2900 3500);
FORCEPROP 3 LASTPIN (-2900 3550) SIG_NAME GND\g
J 0
(-2890 3560);
DISPLAY 0.659574 (-2890 3560);
PAINT MONO (-2890 3560);
DISPLAY INVISIBLE (-2890 3560);
FORCEPROP 1 LAST SIZE 1B
J 0
(-2825 3450);
DISPLAY 1.170213 (-2825 3450);
PAINT GREEN (-2825 3450);
DISPLAY INVISIBLE (-2825 3450);
FORCEPROP 2 LAST CDS_LIB mstr_symbols
J 0
(-2900 3500);
PAINT ORANGE (-2900 3500);
DISPLAY INVISIBLE (-2900 3500);
FORCEPROP 1 LAST VOLTAGE 0.0V
J 0
(-2945 3457);
DISPLAY 0.340426 (-2945 3457);
PAINT SKYBLUE (-2945 3457);
DISPLAY INVISIBLE (-2945 3457);
FORCEPROP 1 LAST BODY_TYPE PLUMBING
J 0
(-2945 3457);
DISPLAY 0.340426 (-2945 3457);
PAINT GREEN (-2945 3457);
DISPLAY INVISIBLE (-2945 3457);
FORCEPROP 1 LAST HDL_POWER GND
J 0
(-2900 3650);
DISPLAY 0.702128 (-2900 3650);
PAINT GREEN (-2900 3650);
DISPLAY INVISIBLE (-2900 3650);
FORCEPROP 1 LAST PATH I92
J 0
(-2825 3500);
DISPLAY 0.872340 (-2825 3500);
PAINT AQUA (-2825 3500);
DISPLAY INVISIBLE (-2825 3500);
FORCEADD GND..1
(-2850 900);
FORCEPROP 3 LASTPIN (-2850 950) SIG_NAME GND\g
J 0
(-2840 960);
DISPLAY 0.659574 (-2840 960);
PAINT MONO (-2840 960);
DISPLAY INVISIBLE (-2840 960);
FORCEPROP 1 LAST HDL_POWER GND
J 0
(-2850 1050);
DISPLAY 0.702128 (-2850 1050);
PAINT GREEN (-2850 1050);
DISPLAY INVISIBLE (-2850 1050);
FORCEPROP 1 LAST BODY_TYPE PLUMBING
J 0
(-2895 857);
DISPLAY 0.340426 (-2895 857);
PAINT GREEN (-2895 857);
DISPLAY INVISIBLE (-2895 857);
FORCEPROP 1 LAST VOLTAGE 0.0V
J 0
(-2895 857);
DISPLAY 0.340426 (-2895 857);
PAINT SKYBLUE (-2895 857);
DISPLAY INVISIBLE (-2895 857);
FORCEPROP 2 LAST CDS_LIB mstr_symbols
J 0
(-2850 900);
PAINT ORANGE (-2850 900);
DISPLAY INVISIBLE (-2850 900);
FORCEPROP 1 LAST SIZE 1B
J 0
(-2775 850);
DISPLAY 1.170213 (-2775 850);
PAINT GREEN (-2775 850);
DISPLAY INVISIBLE (-2775 850);
FORCEPROP 1 LAST PATH I93
J 0
(-2775 900);
DISPLAY 0.872340 (-2775 900);
PAINT AQUA (-2775 900);
DISPLAY INVISIBLE (-2775 900);
FORCEADD RES..1
(-2475 4000);
FORCEPROP 1 LASTPIN (-2575 4000) $PN 1
J 0
(-2563 4012);
DISPLAY 0.617021 (-2563 4012);
PAINT MONO (-2563 4012);
FORCEPROP 1 LAST LOCATION R5D4
J 0
(-2700 4000);
DISPLAY 0.617021 (-2700 4000);
PAINT AQUA (-2700 4000);
FORCEPROP 1 LAST PACK_TYPE 0402
J 0
(-2400 3950);
DISPLAY 0.617021 (-2400 3950);
PAINT SKYBLUE (-2400 3950);
FORCEPROP 1 LAST TOLERANCE 1.0%
J 0
(-2650 3950);
DISPLAY 0.617021 (-2650 3950);
PAINT SKYBLUE (-2650 3950);
FORCEPROP 1 LAST VALUE 240
J 2
(-2675 3950);
DISPLAY 0.617021 (-2675 3950);
PAINT SKYBLUE (-2675 3950);
FORCEPROP 1 LAST WATTAGE 1/16W
J 2
(-2425 3950);
DISPLAY 0.617021 (-2425 3950);
PAINT SKYBLUE (-2425 3950);
FORCEPROP 1 LASTPIN (-2375 4000) $PN 2
J 0
(-2413 4012);
DISPLAY 0.617021 (-2413 4012);
PAINT MONO (-2413 4012);
FORCEPROP 1 LAST MATERIAL CHIP
J 0
(-2275 3950);
DISPLAY 0.617021 (-2275 3950);
PAINT SKYBLUE (-2275 3950);
FORCEPROP 1 LAST PART_NUMBER G21796-294
J 0
(-2350 4000);
DISPLAY 0.617021 (-2350 4000);
PAINT BLUE (-2350 4000);
FORCEPROP 2 LAST SEC 1
J 0
(-2525 4200);
DISPLAY 0.680851 (-2525 4200);
PAINT MONO (-2525 4200);
DISPLAY INVISIBLE (-2525 4200);
FORCEPROP 2 LAST SEC_TYPE 0402
J 0
(-2525 4200);
DISPLAY 1.021277 (-2525 4200);
PAINT ORANGE (-2525 4200);
DISPLAY INVISIBLE (-2525 4200);
FORCEPROP 2 LAST ROOM PROC_SIDEBAND
J 0
(-2125 4100);
PAINT MONO (-2125 4100);
DISPLAY INVISIBLE (-2125 4100);
FORCEPROP 2 LAST CDS_LIB mstr_discrete
J 0
(-2475 4000);
PAINT ORANGE (-2475 4000);
DISPLAY INVISIBLE (-2475 4000);
FORCEPROP 2 LAST BOM_COST PROC
J 0
(-2475 4000);
PAINT MONO (-2475 4000);
DISPLAY INVISIBLE (-2475 4000);
FORCEPROP 1 LAST PATH I96
J 0
(-2525 4150);
DISPLAY 0.978723 (-2525 4150);
PAINT WHITE (-2525 4150);
DISPLAY INVISIBLE (-2525 4150);
FORCEPROP 2 LAST CDS_LOCATION R5D4
J 0
(-2750 4025);
DISPLAY 0.617021 (-2750 4025);
PAINT AQUA (-2750 4025);
DISPLAY INVISIBLE (-2750 4025);
FORCEADD RES..1
(-575 3200);
FORCEPROP 1 LAST WATTAGE 1/16W
J 2
(-525 3150);
DISPLAY 0.617021 (-525 3150);
PAINT SKYBLUE (-525 3150);
FORCEPROP 1 LAST MATERIAL EMPTY
J 0
(-375 3150);
DISPLAY 0.617021 (-375 3150);
PAINT RED (-375 3150);
FORCEPROP 1 LASTPIN (-475 3200) $PN 2
J 0
(-513 3212);
DISPLAY 0.617021 (-513 3212);
PAINT ORANGE (-513 3212);
FORCEPROP 1 LASTPIN (-675 3200) $PN 1
J 0
(-663 3212);
DISPLAY 0.617021 (-663 3212);
PAINT ORANGE (-663 3212);
FORCEPROP 1 LAST TOLERANCE 1.0%
J 0
(-750 3150);
DISPLAY 0.617021 (-750 3150);
PAINT SKYBLUE (-750 3150);
FORCEPROP 1 LAST VALUE 240
J 2
(-775 3150);
DISPLAY 0.617021 (-775 3150);
PAINT SKYBLUE (-775 3150);
FORCEPROP 1 LAST PART_NUMBER G21796-294
J 0
(-425 3200);
DISPLAY 0.617021 (-425 3200);
PAINT BLUE (-425 3200);
FORCEPROP 1 LAST PACK_TYPE 0402
J 0
(-500 3150);
DISPLAY 0.617021 (-500 3150);
PAINT SKYBLUE (-500 3150);
FORCEPROP 1 LAST LOCATION R4P1
J 0
(-800 3200);
DISPLAY 0.617021 (-800 3200);
PAINT AQUA (-800 3200);
FORCEPROP 1 LAST PATH I98
J 0
(-625 3350);
DISPLAY 0.978723 (-625 3350);
PAINT WHITE (-625 3350);
DISPLAY INVISIBLE (-625 3350);
FORCEPROP 2 LAST CDS_LOCATION R4P1
J 0
(-850 3225);
DISPLAY 0.617021 (-850 3225);
PAINT AQUA (-850 3225);
DISPLAY INVISIBLE (-850 3225);
FORCEPROP 0 LAST ROOM PROC_SIDEBAND
J 0
(-200 3350);
DISPLAY 1.021277 (-200 3350);
PAINT ORANGE (-200 3350);
DISPLAY INVISIBLE (-200 3350);
FORCEPROP 2 LAST SEC 1
J 0
(-625 3400);
DISPLAY 0.680851 (-625 3400);
PAINT MONO (-625 3400);
DISPLAY INVISIBLE (-625 3400);
FORCEPROP 2 LAST SEC_TYPE 0402
J 0
(-625 3400);
DISPLAY 1.021277 (-625 3400);
PAINT ORANGE (-625 3400);
DISPLAY INVISIBLE (-625 3400);
FORCEPROP 2 LAST CDS_LIB mstr_discrete
J 0
(-575 3200);
PAINT ORANGE (-575 3200);
DISPLAY INVISIBLE (-575 3200);
FORCEPROP 2 LAST BOM_COST PROC
J 0
(-575 3200);
PAINT MONO (-575 3200);
DISPLAY INVISIBLE (-575 3200);
FORCEADD RES..1
(-425 1050);
FORCEPROP 1 LAST WATTAGE 1/16W
J 2
(-375 1000);
DISPLAY 0.617021 (-375 1000);
PAINT SKYBLUE (-375 1000);
FORCEPROP 1 LAST LOCATION R3D13
J 0
(-650 1050);
DISPLAY 0.617021 (-650 1050);
PAINT AQUA (-650 1050);
FORCEPROP 1 LAST VALUE 240
J 2
(-625 1000);
DISPLAY 0.617021 (-625 1000);
PAINT SKYBLUE (-625 1000);
FORCEPROP 1 LASTPIN (-325 1050) $PN 2
J 0
(-363 1062);
DISPLAY 0.617021 (-363 1062);
PAINT ORANGE (-363 1062);
FORCEPROP 1 LAST TOLERANCE 1.0%
J 0
(-600 1000);
DISPLAY 0.617021 (-600 1000);
PAINT SKYBLUE (-600 1000);
FORCEPROP 1 LASTPIN (-525 1050) $PN 1
J 0
(-513 1062);
DISPLAY 0.617021 (-513 1062);
PAINT ORANGE (-513 1062);
FORCEPROP 1 LAST MATERIAL EMPTY
J 0
(-225 1000);
DISPLAY 0.617021 (-225 1000);
PAINT RED (-225 1000);
FORCEPROP 1 LAST PACK_TYPE 0402
J 0
(-350 1000);
DISPLAY 0.617021 (-350 1000);
PAINT SKYBLUE (-350 1000);
FORCEPROP 1 LAST PART_NUMBER G21796-294
J 0
(-300 1050);
DISPLAY 0.617021 (-300 1050);
PAINT BLUE (-300 1050);
FORCEPROP 1 LAST PATH I99
J 0
(-475 1200);
DISPLAY 0.978723 (-475 1200);
PAINT WHITE (-475 1200);
DISPLAY INVISIBLE (-475 1200);
FORCEPROP 2 LAST CDS_LOCATION R3D13
J 0
(-725 1075);
DISPLAY 0.617021 (-725 1075);
PAINT AQUA (-725 1075);
DISPLAY INVISIBLE (-725 1075);
FORCEPROP 0 LAST ROOM PROC_SIDEBAND
J 0
(-50 1200);
DISPLAY 1.021277 (-50 1200);
PAINT ORANGE (-50 1200);
DISPLAY INVISIBLE (-50 1200);
FORCEPROP 2 LAST SEC_TYPE 0402
J 0
(-475 1250);
DISPLAY 1.021277 (-475 1250);
PAINT ORANGE (-475 1250);
DISPLAY INVISIBLE (-475 1250);
FORCEPROP 2 LAST SEC 1
J 0
(-475 1250);
DISPLAY 0.680851 (-475 1250);
PAINT MONO (-475 1250);
DISPLAY INVISIBLE (-475 1250);
FORCEPROP 2 LAST BOM_COST PROC
J 0
(-425 1050);
PAINT MONO (-425 1050);
DISPLAY INVISIBLE (-425 1050);
FORCEPROP 2 LAST CDS_LIB mstr_discrete
J 0
(-425 1050);
PAINT ORANGE (-425 1050);
DISPLAY INVISIBLE (-425 1050);
FORCEADD DNS..2
(-420 1470);
PAINT RED (-420 1470);
FORCEPROP 2 LAST CDS_LIB mstr_misc
J 0
(-420 1470);
PAINT ORANGE (-420 1470);
DISPLAY INVISIBLE (-420 1470);
FORCEPROP 1 LAST COMMENT_BODY TRUE
R 1
J 0
(-345 1245);
DISPLAY 0.872340 (-345 1245);
PAINT GREEN (-345 1245);
DISPLAY INVISIBLE (-345 1245);
FORCEADD DNS..2
(-570 2795);
PAINT RED (-570 2795);
FORCEPROP 1 LAST COMMENT_BODY TRUE
R 1
J 0
(-495 2570);
DISPLAY 0.872340 (-495 2570);
PAINT GREEN (-495 2570);
DISPLAY INVISIBLE (-495 2570);
FORCEPROP 2 LAST CDS_LIB mstr_misc
J 0
(-570 2795);
PAINT ORANGE (-570 2795);
DISPLAY INVISIBLE (-570 2795);
FORCEADD DNS..2
(-570 2995);
PAINT RED (-570 2995);
FORCEPROP 2 LAST CDS_LIB mstr_misc
J 0
(-570 2995);
PAINT ORANGE (-570 2995);
DISPLAY INVISIBLE (-570 2995);
FORCEPROP 1 LAST COMMENT_BODY TRUE
R 1
J 0
(-495 2770);
DISPLAY 0.872340 (-495 2770);
PAINT GREEN (-495 2770);
DISPLAY INVISIBLE (-495 2770);
FORCEADD DNS..2
(-470 4195);
PAINT RED (-470 4195);
FORCEPROP 1 LAST COMMENT_BODY TRUE
R 1
J 0
(-395 3970);
DISPLAY 0.872340 (-395 3970);
PAINT GREEN (-395 3970);
DISPLAY INVISIBLE (-395 3970);
FORCEPROP 2 LAST CDS_LIB mstr_misc
J 0
(-470 4195);
PAINT ORANGE (-470 4195);
DISPLAY INVISIBLE (-470 4195);
FORCEADD DNS..2
(-2445 1670);
PAINT RED (-2445 1670);
FORCEPROP 2 LAST CDS_LIB mstr_misc
J 0
(-2445 1670);
PAINT ORANGE (-2445 1670);
DISPLAY INVISIBLE (-2445 1670);
FORCEPROP 1 LAST COMMENT_BODY TRUE
R 1
J 0
(-2370 1445);
DISPLAY 0.872340 (-2370 1445);
PAINT GREEN (-2370 1445);
DISPLAY INVISIBLE (-2370 1445);
FORCEADD CAD_NOTE..1
(-525 2100);
FORCEPROP 0 LAST L1 PLACE PD WITHIN 500 MILS OF CPU1
J 2
(475 1975);
DISPLAY 1.021277 (475 1975);
PAINT ORANGE (475 1975);
FORCEPROP 1 LAST COMMENT_BODY TRUE
J 0
(-500 2200);
DISPLAY 0.978723 (-500 2200);
PAINT ORANGE (-500 2200);
DISPLAY INVISIBLE (-500 2200);
FORCEPROP 2 LAST CDS_LIB mstr_symbols
J 0
(-525 2100);
PAINT ORANGE (-525 2100);
DISPLAY INVISIBLE (-525 2100);
FORCEADD DNS..2
(-2445 1870);
PAINT RED (-2445 1870);
FORCEPROP 2 LAST CDS_LIB mstr_misc
J 0
(-2445 1870);
PAINT ORANGE (-2445 1870);
DISPLAY INVISIBLE (-2445 1870);
FORCEPROP 1 LAST COMMENT_BODY TRUE
R 1
J 0
(-2370 1645);
DISPLAY 0.872340 (-2370 1645);
PAINT GREEN (-2370 1645);
DISPLAY INVISIBLE (-2370 1645);
FORCEADD DNS..2
(-420 645);
PAINT RED (-420 645);
FORCEPROP 1 LAST COMMENT_BODY TRUE
R 1
J 0
(-345 420);
DISPLAY 0.872340 (-345 420);
PAINT GREEN (-345 420);
DISPLAY INVISIBLE (-345 420);
FORCEPROP 2 LAST CDS_LIB mstr_misc
J 0
(-420 645);
PAINT ORANGE (-420 645);
DISPLAY INVISIBLE (-420 645);
FORCEADD DNS..2
(-2445 795);
PAINT RED (-2445 795);
FORCEPROP 2 LAST CDS_LIB mstr_misc
J 0
(-2445 795);
PAINT ORANGE (-2445 795);
DISPLAY INVISIBLE (-2445 795);
FORCEPROP 1 LAST COMMENT_BODY TRUE
R 1
J 0
(-2370 570);
DISPLAY 0.872340 (-2370 570);
PAINT GREEN (-2370 570);
DISPLAY INVISIBLE (-2370 570);
FORCEADD DNS..2
(-2470 4195);
PAINT RED (-2470 4195);
FORCEPROP 2 LAST CDS_LIB mstr_misc
J 0
(-2470 4195);
PAINT ORANGE (-2470 4195);
DISPLAY INVISIBLE (-2470 4195);
FORCEPROP 1 LAST COMMENT_BODY TRUE
R 1
J 0
(-2395 3970);
DISPLAY 0.872340 (-2395 3970);
PAINT GREEN (-2395 3970);
DISPLAY INVISIBLE (-2395 3970);
FORCEADD DNS..2
(-2445 1270);
PAINT RED (-2445 1270);
FORCEPROP 2 LAST CDS_LIB mstr_misc
J 0
(-2445 1270);
PAINT ORANGE (-2445 1270);
DISPLAY INVISIBLE (-2445 1270);
FORCEPROP 1 LAST COMMENT_BODY TRUE
R 1
J 0
(-2370 1045);
DISPLAY 0.872340 (-2370 1045);
PAINT GREEN (-2370 1045);
DISPLAY INVISIBLE (-2370 1045);
FORCEADD DNS..2
(-570 3395);
PAINT RED (-570 3395);
FORCEPROP 1 LAST COMMENT_BODY TRUE
R 1
J 0
(-495 3170);
DISPLAY 0.872340 (-495 3170);
PAINT GREEN (-495 3170);
DISPLAY INVISIBLE (-495 3170);
FORCEPROP 2 LAST CDS_LIB mstr_misc
J 0
(-570 3395);
PAINT ORANGE (-570 3395);
DISPLAY INVISIBLE (-570 3395);
FORCEADD DNS..2
(-570 3195);
PAINT RED (-570 3195);
FORCEPROP 2 LAST CDS_LIB mstr_misc
J 0
(-570 3195);
PAINT ORANGE (-570 3195);
DISPLAY INVISIBLE (-570 3195);
FORCEPROP 1 LAST COMMENT_BODY TRUE
R 1
J 0
(-495 2970);
DISPLAY 0.872340 (-495 2970);
PAINT GREEN (-495 2970);
DISPLAY INVISIBLE (-495 2970);
FORCEADD DNS..2
(-2470 3595);
PAINT RED (-2470 3595);
FORCEPROP 2 LAST CDS_LIB mstr_misc
J 0
(-2470 3595);
PAINT ORANGE (-2470 3595);
DISPLAY INVISIBLE (-2470 3595);
FORCEPROP 1 LAST COMMENT_BODY TRUE
R 1
J 0
(-2395 3370);
DISPLAY 0.872340 (-2395 3370);
PAINT GREEN (-2395 3370);
DISPLAY INVISIBLE (-2395 3370);
FORCEADD DNS..2
(-420 1270);
PAINT RED (-420 1270);
FORCEPROP 2 LAST CDS_LIB mstr_misc
J 0
(-420 1270);
PAINT ORANGE (-420 1270);
DISPLAY INVISIBLE (-420 1270);
FORCEPROP 1 LAST COMMENT_BODY TRUE
R 1
J 0
(-345 1045);
DISPLAY 0.872340 (-345 1045);
PAINT GREEN (-345 1045);
DISPLAY INVISIBLE (-345 1045);
FORCEADD DNS..2
(-420 1045);
PAINT RED (-420 1045);
FORCEPROP 1 LAST COMMENT_BODY TRUE
R 1
J 0
(-345 820);
DISPLAY 0.872340 (-345 820);
PAINT GREEN (-345 820);
DISPLAY INVISIBLE (-345 820);
FORCEPROP 2 LAST CDS_LIB mstr_misc
J 0
(-420 1045);
PAINT ORANGE (-420 1045);
DISPLAY INVISIBLE (-420 1045);
FORCEADD CAD_NOTE..1
(-2425 2825);
FORCEPROP 0 LAST L1 PLACE PD WITHIN 500 MILS OF CPU0
J 2
(-1725 2700);
DISPLAY 1.021277 (-1725 2700);
PAINT ORANGE (-1725 2700);
FORCEPROP 2 LAST CDS_LIB mstr_symbols
J 0
(-2425 2825);
PAINT ORANGE (-2425 2825);
DISPLAY INVISIBLE (-2425 2825);
FORCEPROP 1 LAST COMMENT_BODY TRUE
J 0
(-2400 2925);
DISPLAY 0.978723 (-2400 2925);
PAINT ORANGE (-2400 2925);
DISPLAY INVISIBLE (-2400 2925);
FORCEADD DESIGN_NOTE..1
(-650 3875);
PAINT PURPLE (-650 3875);
FORCEPROP 0 LAST L3 WHEN TXT IS READY
J 0
(-850 3625);
PAINT VIOLET (-850 3625);
FORCEPROP 0 LAST L2 ENABLE ACCORDING TO TABLE
J 0
(-850 3700);
PAINT VIOLET (-850 3700);
FORCEPROP 0 LAST L1 ***TXT IS DISABLED FOR EARLY SILICON
J 0
(-850 3750);
PAINT VIOLET (-850 3750);
FORCEPROP 2 LAST ROOM PVCCIN_CPU1_DECAP_VR
J 0
(-850 3825);
PAINT MONO (-850 3825);
DISPLAY INVISIBLE (-850 3825);
FORCEPROP 1 LAST COMMENT_BODY TRUE
J 0
(-625 3975);
DISPLAY 1.319149 (-625 3975);
PAINT GREEN (-625 3975);
DISPLAY INVISIBLE (-625 3975);
FORCEPROP 2 LAST BOM_COST SM_CONTROLLER
J 0
(-850 3825);
PAINT MONO (-850 3825);
DISPLAY INVISIBLE (-850 3825);
FORCEPROP 2 LAST CDS_LIB mstr_symbols
J 0
(-650 3875);
PAINT ORANGE (-650 3875);
DISPLAY INVISIBLE (-650 3875);
FORCEADD DNS..2
(-2445 1470);
PAINT RED (-2445 1470);
FORCEPROP 2 LAST CDS_LIB mstr_misc
J 0
(-2445 1470);
PAINT ORANGE (-2445 1470);
DISPLAY INVISIBLE (-2445 1470);
FORCEPROP 1 LAST COMMENT_BODY TRUE
R 1
J 0
(-2370 1245);
DISPLAY 0.872340 (-2370 1245);
PAINT GREEN (-2370 1245);
DISPLAY INVISIBLE (-2370 1245);
FORCEADD DNS..2
(-470 4395);
PAINT RED (-470 4395);
FORCEPROP 1 LAST COMMENT_BODY TRUE
R 1
J 0
(-395 4170);
DISPLAY 0.872340 (-395 4170);
PAINT GREEN (-395 4170);
DISPLAY INVISIBLE (-395 4170);
FORCEPROP 2 LAST CDS_LIB mstr_misc
J 0
(-470 4395);
PAINT ORANGE (-470 4395);
DISPLAY INVISIBLE (-470 4395);
FORCEADD INTEL_CORP_BPAGE..1
(4250 200);
FORCEPROP 1 LAST CDS_CON_LAST_MODIFIED Fri Jun 16 17:48:34 2017
J 0
(2825 525);
PAINT ORANGE (2825 525);
DISPLAY INVISIBLE (2825 525);
FORCEPROP 1 LAST CUSTOM_TXT_CDS <CURRENT_DESIGN_SHEET> OF <TOTAL_DESIGN_SHEETS>
J 0
(3750 225);
PAINT ORANGE (3750 225);
FORCEPROP 1 LAST CUSTOM_TXT_CDS <CON_LAST_MODIFIED>
J 0
(250 300);
PAINT ORANGE (250 300);
FORCEPROP 2 LAST CUSTOM_TXT_CDS <XR_PAGE_TITLE>
J 0
(-3640 5450);
DISPLAY 0.638298 (-3640 5450);
PAINT PINK (-3640 5450);
DISPLAY INVISIBLE (-3640 5450);
FORCEPROP 1 LAST SCH_TITLE CPU SIDE BAND: HW STRAPS
J 0
(-3700 250);
DISPLAY 1.212766 (-3700 250);
PAINT ORANGE (-3700 250);
FORCEPROP 1 LAST COMMENT_BODY TRUE
J 0
(4262 212);
DISPLAY 0.468085 (4262 212);
PAINT GREEN (4262 212);
DISPLAY INVISIBLE (4262 212);
FORCEPROP 2 LAST CDS_LIB mstr_symbols
J 0
(4250 200);
PAINT MONO (4250 200);
DISPLAY INVISIBLE (4250 200);
FORCEPROP 2 LAST PAGE_BORDER TRUE
J 0
(-3640 5450);
DISPLAY 0.638298 (-3640 5450);
PAINT PINK (-3640 5450);
DISPLAY INVISIBLE (-3640 5450);
FORCEPROP 2 LAST CDS_XR_PAGE_TITLE CR-90 : @BASEBOARD_FAB2_LIB.BASEBOARD_FAB2(SCH_1):PAGE90
J 0
(-3640 5450);
DISPLAY 0.638298 (-3640 5450);
PAINT PINK (-3640 5450);
DISPLAY INVISIBLE (-3640 5450);
FORCEADD DNS..2
(-2445 1020);
PAINT RED (-2445 1020);
FORCEPROP 2 LAST CDS_LIB mstr_misc
J 0
(-2445 1020);
PAINT ORANGE (-2445 1020);
DISPLAY INVISIBLE (-2445 1020);
FORCEPROP 1 LAST COMMENT_BODY TRUE
R 1
J 0
(-2370 795);
DISPLAY 0.872340 (-2370 795);
PAINT GREEN (-2370 795);
DISPLAY INVISIBLE (-2370 795);
FORCEADD DNS..2
(-2470 3795);
PAINT RED (-2470 3795);
FORCEPROP 2 LAST CDS_LIB mstr_misc
J 0
(-2470 3795);
PAINT ORANGE (-2470 3795);
DISPLAY INVISIBLE (-2470 3795);
FORCEPROP 1 LAST COMMENT_BODY TRUE
R 1
J 0
(-2395 3570);
DISPLAY 0.872340 (-2395 3570);
PAINT GREEN (-2395 3570);
DISPLAY INVISIBLE (-2395 3570);
WIRE 16 -1 (-725 650)(-725 575);
WIRE 16 -1 (-725 850)(-725 650);
WIRE 16 -1 (-725 650)(-525 650);
WIRE 16 -1 (-725 1050)(-725 850);
WIRE 16 -1 (-725 850)(-525 850);
WIRE 16 -1 (-725 1275)(-725 1050);
WIRE 16 -1 (-525 1050)(-725 1050);
WIRE 16 -1 (-525 1275)(-725 1275);
WIRE 16 -1 (-2975 4400)(-2975 4500);
WIRE 16 -1 (-2975 4200)(-2975 4400);
WIRE 16 -1 (-2975 4400)(-2575 4400);
WIRE 16 -1 (-2975 4000)(-2975 4200);
WIRE 16 -1 (-2975 4200)(-2575 4200);
WIRE 16 -1 (-2975 4000)(-2975 3800);
WIRE 16 -1 (-2975 4000)(-2575 4000);
WIRE 16 -1 (-2975 3800)(-2975 3400);
WIRE 16 -1 (-2975 3800)(-2575 3800);
WIRE 16 -1 (-2975 3400)(-2575 3400);
WIRE 16 -1 (-900 2650)(-900 2800);
WIRE 16 -1 (-900 3000)(-900 2800);
WIRE 16 -1 (-900 2800)(-675 2800);
WIRE 16 -1 (-900 3000)(-900 3200);
WIRE 16 -1 (-900 3000)(-675 3000);
WIRE 16 -1 (-900 3400)(-900 3200);
WIRE 16 -1 (-675 3200)(-900 3200);
WIRE 16 -1 (-675 3400)(-900 3400);
WIRE 16 -1 (-825 4575)(-825 4400);
WIRE 16 -1 (-825 4200)(-825 4400);
WIRE 16 -1 (-575 4400)(-825 4400);
WIRE 16 -1 (-575 4200)(-825 4200);
WIRE 16 -1 (-2950 2000)(-2950 1875);
WIRE 16 -1 (-2950 1875)(-2950 1675);
WIRE 16 -1 (-2950 1875)(-2550 1875);
WIRE 16 -1 (-2950 1675)(-2950 1475);
WIRE 16 -1 (-2950 1675)(-2550 1675);
WIRE 16 -1 (-2950 1475)(-2950 1275);
WIRE 16 -1 (-2950 1475)(-2550 1475);
WIRE 16 -1 (-2950 1275)(-2950 800);
WIRE 16 -1 (-2950 1275)(-2550 1275);
WIRE 16 -1 (-2950 800)(-2550 800);
WIRE 16 -1 (-2950 800)(-2975 800);
WIRE 16 -1 (-725 1775)(-725 1675);
WIRE 16 -1 (-725 1675)(-725 1475);
WIRE 16 -1 (-525 1675)(-725 1675);
WIRE 16 -1 (-525 1475)(-725 1475);
WIRE 16 -1 (-1225 2925)(-1225 2775);
WIRE 16 -1 (-1225 2925)(-1225 3075);
WIRE 16 -1 (-1475 2925)(-1225 2925);
WIRE 16 -1 (-1225 3075)(-1225 3200);
WIRE 16 -1 (-1475 3075)(-1225 3075);
WIRE 16 -1 (-1475 3200)(-1225 3200);
WIRE 16 -1 (675 2200)(675 2050);
WIRE 16 -1 (675 2200)(675 2350);
WIRE 16 -1 (425 2200)(675 2200);
WIRE 16 -1 (675 2350)(675 2475);
WIRE 16 -1 (425 2350)(675 2350);
WIRE 16 -1 (425 2475)(675 2475);
WIRE 16 -1 (-2900 3600)(-2900 3550);
WIRE 16 -1 (-2900 3600)(-2575 3600);
WIRE 16 -1 (-2850 1025)(-2850 950);
WIRE 16 -1 (-2850 1025)(-2550 1025);
WIRE 16 -1 (-2425 5000)(-3500 5000);
WIRE 16 -1 (-2425 5000)(-2425 4800);
WIRE 16 -1 (-3500 5000)(-3500 4800);
WIRE 16 -1 (-3500 4800)(-2425 4800);
WIRE 16 273 (1000 1700)(4100 1700);
WIRE 16 273 (1000 2150)(4125 2150);
WIRE 16 273 (1000 2375)(4125 2375);
WIRE 16 273 (4125 2375)(4125 2150);
WIRE 16 273 (1000 1925)(4125 1925);
WIRE 16 273 (4125 2150)(4125 1925);
WIRE 16 273 (4125 1925)(4125 1125);
WIRE 16 273 (1000 2600)(4125 2600);
WIRE 16 273 (4125 2600)(4125 2375);
WIRE 16 273 (1000 2825)(4125 2825);
WIRE 16 273 (4125 2825)(4125 2600);
WIRE 16 273 (4125 1125)(925 1125);
WIRE 16 273 (925 1125)(925 4125);
WIRE 16 273 (1000 3150)(4125 3150);
WIRE 16 273 (4125 3150)(4125 2825);
WIRE 16 273 (1000 3700)(4125 3700);
WIRE 16 273 (4125 3700)(4125 3150);
WIRE 16 273 (925 4125)(4125 4125);
WIRE 16 273 (4125 4125)(4125 3700);
WIRE 16 -1 (-475 3000)(425 3000);
FORCEPROP 2 LAST SIG_NAME PD_CPU0_DMIMODE_OVERRIDE
J 0
(-160 3010);
DISPLAY 0.617021 (-160 3010);
PAINT ORANGE (-160 3010);
WIRE 16 -1 (-3525 5025)(-3525 4775);
WIRE 16 -1 (-2400 4775)(-3525 4775);
WIRE 16 -1 (-2400 5025)(-3525 5025);
WIRE 16 -1 (-2400 5025)(-2400 4775);
WIRE 16 273 (2000 4100)(2000 1150);
WIRE 16 -1 (500 1275)(-325 1275);
FORCEPROP 2 LAST SIG_NAME PD_CPU1_TXT_PLTEN
J 0
(15 1285);
DISPLAY 0.617021 (15 1285);
PAINT ORANGE (15 1285);
WIRE 16 -1 (450 1675)(-325 1675);
FORCEPROP 2 LAST SIG_NAME PU_CPU1_SOCKET_ID_0
J 0
(15 1685);
DISPLAY 0.617021 (15 1685);
PAINT ORANGE (15 1685);
WIRE 16 -1 (450 1475)(-325 1475);
FORCEPROP 2 LAST SIG_NAME PU_CPU1_SOCKET_ID_1
J 0
(15 1485);
DISPLAY 0.617021 (15 1485);
PAINT ORANGE (15 1485);
WIRE 16 -1 (425 3200)(-475 3200);
FORCEPROP 2 LAST SIG_NAME PD_CPU0_BIST_ENABLE
J 0
(-135 3210);
DISPLAY 0.617021 (-135 3210);
PAINT ORANGE (-135 3210);
WIRE 16 -1 (425 3400)(-475 3400);
FORCEPROP 2 LAST SIG_NAME PD_CPU0_TXT_PLTEN
J 0
(-135 3410);
DISPLAY 0.617021 (-135 3410);
PAINT ORANGE (-135 3410);
WIRE 16 -1 (-850 2475)(225 2475);
FORCEPROP 2 LAST SIG_NAME PD_CPU1_TEST14
J 0
(-775 2485);
DISPLAY 0.617021 (-775 2485);
PAINT ORANGE (-775 2485);
WIRE 16 -1 (225 2350)(-850 2350);
FORCEPROP 2 LAST SIG_NAME PD_CPU1_TEST13
J 0
(-775 2360);
DISPLAY 0.617021 (-775 2360);
PAINT ORANGE (-775 2360);
WIRE 16 -1 (-475 2800)(425 2800);
FORCEPROP 2 LAST SIG_NAME PD_CPU0_KSFC_DIS
J 0
(-140 2802);
DISPLAY 0.617021 (-140 2802);
PAINT ORANGE (-140 2802);
WIRE 16 -1 (225 2200)(-850 2200);
FORCEPROP 2 LAST SIG_NAME PD_CPU1_TEST12
J 0
(-800 2210);
DISPLAY 0.617021 (-800 2210);
PAINT ORANGE (-800 2210);
WIRE 16 -1 (500 1050)(-325 1050);
FORCEPROP 2 LAST SIG_NAME PD_CPU1_BIST_ENABLE
J 0
(15 1060);
DISPLAY 0.617021 (15 1060);
PAINT ORANGE (15 1060);
WIRE 16 273 (1725 4100)(1725 1150);
WIRE 16 273 (2300 4100)(2300 1150);
WIRE 16 273 (2575 4100)(2575 1150);
WIRE 16 273 (1000 3475)(4100 3475);
WIRE 16 -1 (-1400 1675)(-2350 1675);
FORCEPROP 2 LAST SIG_NAME H_CPU1_BMCINIT
J 0
(-2035 1685);
DISPLAY 0.617021 (-2035 1685);
PAINT ORANGE (-2035 1685);
WIRE 16 -1 (-1400 1875)(-2350 1875);
FORCEPROP 2 LAST SIG_NAME PU_CPU1_FRMAGENT
J 0
(-2035 1885);
DISPLAY 0.617021 (-2035 1885);
PAINT ORANGE (-2035 1885);
WIRE 16 273 (975 1425)(4075 1425);
WIRE 16 -1 (-3500 2525)(-3500 2325);
WIRE 16 -1 (-3500 2325)(-2425 2325);
WIRE 16 -1 (-2425 2525)(-3500 2525);
WIRE 16 -1 (-2425 2525)(-2425 2325);
WIRE 16 -1 (-3525 2550)(-3525 2300);
WIRE 16 -1 (-2400 2300)(-3525 2300);
WIRE 16 -1 (-2400 2550)(-3525 2550);
WIRE 16 -1 (-2400 2550)(-2400 2300);
WIRE 16 273 (1000 3925)(4100 3925);
WIRE 16 -1 (-325 850)(625 850);
FORCEPROP 2 LAST SIG_NAME PD_CPU1_DMIMODE_OVERRIDE
J 0
(-10 860);
DISPLAY 0.617021 (-10 860);
PAINT ORANGE (-10 860);
WIRE 16 -1 (-325 650)(625 650);
FORCEPROP 2 LAST SIG_NAME PD_CPU1_KSFC_DIS
J 0
(10 652);
DISPLAY 0.617021 (10 652);
PAINT ORANGE (10 652);
WIRE 16 -1 (-1350 4200)(-2375 4200);
FORCEPROP 2 LAST SIG_NAME H_CPU0_BMCINIT
J 0
(-2035 4210);
DISPLAY 0.617021 (-2035 4210);
PAINT ORANGE (-2035 4210);
WIRE 16 -1 (-2375 4000)(-1350 4000);
FORCEPROP 2 LAST SIG_NAME PU_CPU0_TXT_AGENT
J 0
(-2035 4010);
DISPLAY 0.617021 (-2035 4010);
PAINT ORANGE (-2035 4010);
WIRE 16 -1 (-2350 800)(-1375 800);
FORCEPROP 2 LAST SIG_NAME PU_CPU1_LEGACY_SKT
J 0
(-2010 810);
DISPLAY 0.617021 (-2010 810);
PAINT ORANGE (-2010 810);
WIRE 16 -1 (-2350 1025)(-1375 1025);
FORCEPROP 2 LAST SIG_NAME PD_CPU1_EAR_N
J 0
(-1985 1035);
DISPLAY 0.617021 (-1985 1035);
PAINT ORANGE (-1985 1035);
WIRE 16 -1 (-1350 4400)(-2375 4400);
FORCEPROP 2 LAST SIG_NAME PU_CPU0_FRMAGENT
J 0
(-2035 4410);
DISPLAY 0.617021 (-2035 4410);
PAINT ORANGE (-2035 4410);
WIRE 16 -1 (-1350 3800)(-2375 3800);
FORCEPROP 2 LAST SIG_NAME PU_CPU0_SAFE_MODE_BOOT
J 0
(-2035 3810);
DISPLAY 0.617021 (-2035 3810);
PAINT ORANGE (-2035 3810);
WIRE 16 -1 (-2375 3600)(-1350 3600);
FORCEPROP 2 LAST SIG_NAME PD_CPU0_EAR_N
J 0
(-2060 3610);
DISPLAY 0.617021 (-2060 3610);
PAINT ORANGE (-2060 3610);
WIRE 16 -1 (-1350 3400)(-2375 3400);
FORCEPROP 2 LAST SIG_NAME PU_CPU0_LEGACY_SKT
J 0
(-2035 3410);
DISPLAY 0.617021 (-2035 3410);
PAINT ORANGE (-2035 3410);
WIRE 16 -1 (-2750 3200)(-1675 3200);
FORCEPROP 2 LAST SIG_NAME PD_CPU0_TEST14
J 0
(-2675 3210);
DISPLAY 0.617021 (-2675 3210);
PAINT ORANGE (-2675 3210);
WIRE 16 -1 (-1675 3075)(-2750 3075);
FORCEPROP 2 LAST SIG_NAME PD_CPU0_TEST13
J 0
(-2675 3085);
DISPLAY 0.617021 (-2675 3085);
PAINT ORANGE (-2675 3085);
WIRE 16 -1 (-1675 2925)(-2750 2925);
FORCEPROP 2 LAST SIG_NAME PD_CPU0_TEST12
J 0
(-2700 2935);
DISPLAY 0.617021 (-2700 2935);
PAINT ORANGE (-2700 2935);
WIRE 16 -1 (-1400 1275)(-2350 1275);
FORCEPROP 2 LAST SIG_NAME PU_CPU1_SAFE_MODE_BOOT
J 0
(-2060 1285);
DISPLAY 0.617021 (-2060 1285);
PAINT ORANGE (-2060 1285);
WIRE 16 -1 (475 4200)(-375 4200);
FORCEPROP 2 LAST SIG_NAME PU_CPU0_SOCKET_ID_1
J 0
(-60 4210);
DISPLAY 0.617021 (-60 4210);
PAINT ORANGE (-60 4210);
WIRE 16 -1 (475 4400)(-375 4400);
FORCEPROP 2 LAST SIG_NAME PU_CPU0_SOCKET_ID_0
J 0
(-60 4410);
DISPLAY 0.617021 (-60 4410);
PAINT ORANGE (-60 4410);
WIRE 16 -1 (-1400 1475)(-2350 1475);
FORCEPROP 2 LAST SIG_NAME PU_CPU1_TXT_AGENT
J 0
(-2035 1485);
DISPLAY 0.617021 (-2035 1485);
PAINT ORANGE (-2035 1485);
DOT 1 (-725 650);
DOT 1 (-900 3000);
DOT 1 (-725 1675);
DOT 1 (-725 1050);
DOT 1 (-900 3200);
DOT 1 (4125 3700);
DOT 1 (-2950 1475);
DOT 1 (-2950 1675);
DOT 1 (-2950 1875);
DOT 1 (-2975 4000);
DOT 1 (-725 850);
DOT 1 (-1225 3075);
DOT 1 (-2975 4200);
DOT 1 (-2975 4400);
DOT 1 (-825 4400);
DOT 1 (675 2200);
DOT 1 (675 2350);
DOT 1 (4125 1925);
DOT 1 (4125 2150);
DOT 1 (4125 2600);
DOT 1 (4125 2825);
DOT 1 (4125 3150);
DOT 1 (-2975 3800);
DOT 1 (-900 2800);
DOT 1 (-1225 2925);
DOT 1 (-2950 800);
DOT 1 (-2950 1275);
DOT 1 (4125 2375);
FORCENOTE
0: CNX FETCHES HASH FROM LBG
(2625 1250) 0;
DISPLAY LEFT (2625 1250);
DISPLAY 1.021277 (2625 1250);
PAINT PURPLE (2625 1250);
FORCENOTE
KSFC=KEY SELECT FROM CHIPSET: SKX IGNORE
(2600 1350) 0;
DISPLAY LEFT (2600 1350);
DISPLAY 1.021277 (2600 1350);
PAINT PURPLE (2600 1350);
FORCENOTE
1: F/W IS LOCAL TO THIS SOCKET'S PCH
(2650 1550) 0;
DISPLAY LEFT (2650 1550);
DISPLAY 1.021277 (2650 1550);
PAINT PURPLE (2650 1550);
FORCENOTE
TP FAB1 POP R3D13 0111
(-75 975) 0;
DISPLAY LEFT (-75 975);
DISPLAY 1.021277 (-75 975);
PAINT RED (-75 975);
FORCENOTE
TP FAB1 NOPOP RES R3D13 0418
(-75 925) 0;
DISPLAY LEFT (-75 925);
DISPLAY 1.021277 (-75 925);
PAINT RED (-75 925);
FORCENOTE
TP FAB1 NOPOP RES R7P14 0111
(-75 775) 0;
DISPLAY LEFT (-75 775);
DISPLAY 1.021277 (-75 775);
PAINT RED (-75 775);
FORCENOTE
TP FAB1 POP RES R4P1 0111
(-200 3100) 0;
DISPLAY LEFT (-200 3100);
DISPLAY 1.021277 (-200 3100);
PAINT RED (-200 3100);
FORCENOTE
TP FAB1 NOPOP RES R4P1 0418
(-200 3050) 0;
DISPLAY LEFT (-200 3050);
DISPLAY 1.021277 (-200 3050);
PAINT RED (-200 3050);
FORCENOTE
MCI_SOCKET_ID[1..0]
(1025 2475) 0;
DISPLAY LEFT (1025 2475);
DISPLAY 0.893617 (1025 2475);
PAINT PURPLE (1025 2475);
FORCENOTE
PD
(1825 2250) 0;
DISPLAY LEFT (1825 2250);
DISPLAY 0.893617 (1825 2250);
PAINT PURPLE (1825 2250);
FORCENOTE
1
(2125 2025) 0;
DISPLAY LEFT (2125 2025);
DISPLAY 0.893617 (2125 2025);
PAINT PURPLE (2125 2025);
FORCENOTE
1
(2425 3025) 0;
DISPLAY LEFT (2425 3025);
DISPLAY 1.106383 (2425 3025);
PAINT PURPLE (2425 3025);
FORCENOTE
1
(2150 3025) 0;
DISPLAY LEFT (2150 3025);
DISPLAY 1.106383 (2150 3025);
PAINT PURPLE (2150 3025);
FORCENOTE
0
(2400 3575) 0;
DISPLAY LEFT (2400 3575);
DISPLAY 0.893617 (2400 3575);
PAINT PURPLE (2400 3575);
FORCENOTE
PD
(1825 2700) 0;
DISPLAY LEFT (1825 2700);
DISPLAY 0.723404 (1825 2700);
PAINT PURPLE (1825 2700);
FORCENOTE
00
(2150 2475) 0;
DISPLAY LEFT (2150 2475);
DISPLAY 0.893617 (2150 2475);
PAINT PURPLE (2150 2475);
FORCENOTE
01
(2425 2475) 0;
DISPLAY LEFT (2425 2475);
DISPLAY 0.893617 (2425 2475);
PAINT PURPLE (2425 2475);
FORCENOTE
LEGACY CPU = 00
(2725 2475) 0;
DISPLAY LEFT (2725 2475);
DISPLAY 0.893617 (2725 2475);
PAINT PURPLE (2725 2475);
FORCENOTE
EXTERNAL ALIGNMENT OF RESET
(2600 2075) 0;
DISPLAY LEFT (2600 2075);
DISPLAY 1.021277 (2600 2075);
PAINT PURPLE (2600 2075);
FORCENOTE
0
(2150 2250) 0;
DISPLAY LEFT (2150 2250);
DISPLAY 0.893617 (2150 2250);
PAINT PURPLE (2150 2250);
FORCENOTE
BMCINIT
(1025 2250) 0;
DISPLAY LEFT (1025 2250);
DISPLAY 0.893617 (1025 2250);
PAINT PURPLE (1025 2250);
FORCENOTE
MCI_FRMAGENT
(1025 2700) 0;
DISPLAY LEFT (1025 2700);
DISPLAY 0.893617 (1025 2700);
PAINT PURPLE (1025 2700);
FORCENOTE
MCI_TXT_PLTEN
(1025 3025) 0;
DISPLAY LEFT (1025 3025);
DISPLAY 0.893617 (1025 3025);
PAINT PURPLE (1025 3025);
FORCENOTE
EAR_N
(1025 2025) 0;
DISPLAY LEFT (1025 2025);
DISPLAY 0.893617 (1025 2025);
PAINT PURPLE (1025 2025);
FORCENOTE
LEGACY_SXT
(1025 1800) 0;
DISPLAY LEFT (1025 1800);
DISPLAY 0.893617 (1025 1800);
PAINT PURPLE (1025 1800);
FORCENOTE
PU
(1825 1550) 0;
DISPLAY LEFT (1825 1550);
DISPLAY 0.893617 (1825 1550);
PAINT PURPLE (1825 1550);
FORCENOTE
0: NON-LEGACY. DMI3 IS NOT INITIALIZED
(2600 1725) 0;
DISPLAY LEFT (2600 1725);
DISPLAY 1.021277 (2600 1725);
PAINT PURPLE (2600 1725);
FORCENOTE
DMI MODE
(2650 1625) 0;
DISPLAY LEFT (2650 1625);
DISPLAY 1.021277 (2650 1625);
PAINT PURPLE (2650 1625);
FORCENOTE
1
(2150 1550) 0;
DISPLAY LEFT (2150 1550);
DISPLAY 1.106383 (2150 1550);
PAINT PURPLE (2150 1550);
FORCENOTE
STRAPS (CPU1) 
(-3425 2400) 0;
DISPLAY LEFT (-3425 2400);
DISPLAY 1.595745 (-3425 2400);
PAINT PURPLE (-3425 2400);
FORCENOTE
0: CPU IS NOT A TXT AGENT
(2725 3300) 0;
DISPLAY LEFT (2725 3300);
DISPLAY 0.893617 (2725 3300);
PAINT PURPLE (2725 3300);
FORCENOTE
      LEGACY CPU
(2425 3200) 0;
DISPLAY LEFT (2425 3200);
DISPLAY 0.893617 (2425 3200);
PAINT PURPLE (2425 3200);
FORCENOTE
(FOLLOW PDG P202)
(2675 3150) 0;
DISPLAY LEFT (2675 3150);
DISPLAY 0.808511 (2675 3150);
PAINT PURPLE (2675 3150);
FORCENOTE
1: F/W IS LOCAL TO THIS SOCKET'S PCH
(2600 1800) 0;
DISPLAY LEFT (2600 1800);
DISPLAY 1.021277 (2600 1800);
PAINT PURPLE (2600 1800);
FORCENOTE
BOOT MODE OPERATION
(2600 1875) 0;
DISPLAY LEFT (2600 1875);
DISPLAY 1.021277 (2600 1875);
PAINT PURPLE (2600 1875);
FORCENOTE
0:STALL INTERNAL_RESET FLOW
(2625 1950) 0;
DISPLAY LEFT (2625 1950);
DISPLAY 1.021277 (2625 1950);
PAINT PURPLE (2625 1950);
FORCENOTE
0: NON-LEGACY. DMI3 IS NOT INITIALIZED
(2650 1475) 0;
DISPLAY LEFT (2650 1475);
DISPLAY 1.021277 (2650 1475);
PAINT PURPLE (2650 1475);
FORCENOTE
1: CPU HAULTS UNTIL BMC RELEASES BOOT FLOW
(2725 2250) 0;
DISPLAY LEFT (2725 2250);
DISPLAY 0.893617 (2725 2250);
PAINT PURPLE (2725 2250);
FORCENOTE
0: NORMAL BOOT FLOW
(2725 2200) 0;
DISPLAY LEFT (2725 2200);
DISPLAY 0.893617 (2725 2200);
PAINT PURPLE (2725 2200);
FORCENOTE
NOTE: MUST BE SET FOR ALL PROCESSORS
(2650 2925) 0;
DISPLAY LEFT (2650 2925);
DISPLAY 0.893617 (2650 2925);
PAINT PURPLE (2650 2925);
FORCENOTE
0: TXT DISABLED
(2725 2975) 0;
DISPLAY LEFT (2725 2975);
DISPLAY 0.893617 (2725 2975);
PAINT PURPLE (2725 2975);
FORCENOTE
      IN THE SYSTEM
(2400 2875) 0;
DISPLAY LEFT (2400 2875);
DISPLAY 0.893617 (2400 2875);
PAINT PURPLE (2400 2875);
FORCENOTE
CPU DMI PORT MODE
(2675 2750) 0;
DISPLAY LEFT (2675 2750);
DISPLAY 0.893617 (2675 2750);
PAINT PURPLE (2675 2750);
FORCENOTE
0: PCIE MODE
(2725 2650) 0;
DISPLAY LEFT (2725 2650);
DISPLAY 0.893617 (2725 2650);
PAINT PURPLE (2725 2650);
FORCENOTE
NON-LEGACY CPUS = 01 OR 10 OR 11
(2725 2425) 0;
DISPLAY LEFT (2725 2425);
DISPLAY 0.893617 (2725 2425);
PAINT PURPLE (2725 2425);
FORCENOTE
1: CNX FETCHES HASH FROM CPU
(2600 1300) 0;
DISPLAY LEFT (2600 1300);
DISPLAY 1.021277 (2600 1300);
PAINT PURPLE (2600 1300);
FORCENOTE
NOTE: PIN SHOULD ONLY BE ASSERTED ON
(2675 3250) 0;
DISPLAY LEFT (2675 3250);
DISPLAY 0.893617 (2675 3250);
PAINT PURPLE (2675 3250);
FORCENOTE
1: CPU IS TXT AGENT
(2725 3350) 0;
DISPLAY LEFT (2725 3350);
DISPLAY 0.893617 (2725 3350);
PAINT PURPLE (2725 3350);
FORCENOTE
0: SAFE MODE BOOT DISABLED
(2725 3525) 0;
DISPLAY LEFT (2725 3525);
DISPLAY 0.893617 (2725 3525);
PAINT PURPLE (2725 3525);
FORCENOTE
1: SAFE MODE BOOT ENABLED
(2725 3575) 0;
DISPLAY LEFT (2725 3575);
DISPLAY 0.893617 (2725 3575);
PAINT PURPLE (2725 3575);
FORCENOTE
SAFE MODE BOOT (DISABLES CLOCK GATING)
(2675 3625) 0;
DISPLAY LEFT (2675 3625);
DISPLAY 0.893617 (2675 3625);
PAINT PURPLE (2675 3625);
FORCENOTE
1
(2400 3800) 0;
DISPLAY LEFT (2400 3800);
DISPLAY 0.893617 (2400 3800);
PAINT PURPLE (2400 3800);
FORCENOTE
(DEFAULT)
(2050 3975) 0;
DISPLAY LEFT (2050 3975);
DISPLAY 0.723404 (2050 3975);
PAINT PURPLE (2050 3975);
FORCENOTE
PU/PD
(1800 3975) 0;
DISPLAY LEFT (1800 3975);
DISPLAY 0.723404 (1800 3975);
PAINT PURPLE (1800 3975);
FORCENOTE
SKX PIN NAME
(1125 4050) 0;
DISPLAY LEFT (1125 4050);
DISPLAY 0.893617 (1125 4050);
PAINT PURPLE (1125 4050);
FORCENOTE
0
(2400 2700) 0;
DISPLAY LEFT (2400 2700);
DISPLAY 0.914894 (2400 2700);
PAINT PURPLE (2400 2700);
FORCENOTE
MCI_TXT_AGENT
(1025 3350) 0;
DISPLAY LEFT (1025 3350);
DISPLAY 0.893617 (1025 3350);
PAINT PURPLE (1025 3350);
FORCENOTE
0
(2400 3350) 0;
DISPLAY LEFT (2400 3350);
DISPLAY 1.106383 (2400 3350);
PAINT PURPLE (2400 3350);
FORCENOTE
1
(2175 1800) 0;
DISPLAY LEFT (2175 1800);
DISPLAY 1.106383 (2175 1800);
PAINT PURPLE (2175 1800);
FORCENOTE
1
(2150 1275) 0;
DISPLAY LEFT (2150 1275);
DISPLAY 1.106383 (2150 1275);
PAINT PURPLE (2150 1275);
FORCENOTE
1
(2450 1275) 0;
DISPLAY LEFT (2450 1275);
DISPLAY 1.106383 (2450 1275);
PAINT PURPLE (2450 1275);
FORCENOTE
0
(2450 1800) 0;
DISPLAY LEFT (2450 1800);
DISPLAY 1.106383 (2450 1800);
PAINT PURPLE (2450 1800);
FORCENOTE
PD
(1825 3350) 0;
DISPLAY LEFT (1825 3350);
DISPLAY 0.893617 (1825 3350);
PAINT PURPLE (1825 3350);
FORCENOTE
0
(2125 3575) 0;
DISPLAY LEFT (2125 3575);
DISPLAY 0.893617 (2125 3575);
PAINT PURPLE (2125 3575);
FORCENOTE
KSFC_DIS
(1075 1250) 0;
DISPLAY LEFT (1075 1250);
DISPLAY 1.021277 (1075 1250);
PAINT PURPLE (1075 1250);
FORCENOTE
DMIMODE_OVERRIDE
(1050 1550) 0;
DISPLAY LEFT (1050 1550);
DISPLAY 0.893617 (1050 1550);
PAINT PURPLE (1050 1550);
FORCENOTE
SERVICE PROCESSOR BOOT MODE
(2675 2300) 0;
DISPLAY LEFT (2675 2300);
DISPLAY 0.893617 (2675 2300);
PAINT PURPLE (2675 2300);
FORCENOTE
0
(2450 2250) 0;
DISPLAY LEFT (2450 2250);
DISPLAY 0.893617 (2450 2250);
PAINT PURPLE (2450 2250);
FORCENOTE
1
(2125 2700) 0;
DISPLAY LEFT (2125 2700);
DISPLAY 0.893617 (2125 2700);
PAINT PURPLE (2125 2700);
FORCENOTE
1: TXT ENABLED
(2725 3025) 0;
DISPLAY LEFT (2725 3025);
DISPLAY 0.893617 (2725 3025);
PAINT PURPLE (2725 3025);
FORCENOTE
TXT ENABLE
(2675 3075) 0;
DISPLAY LEFT (2675 3075);
DISPLAY 0.893617 (2675 3075);
PAINT PURPLE (2675 3075);
FORCENOTE
TXT AGENT (DRIVES TXT TRANSACTIONS)
(2675 3400) 0;
DISPLAY LEFT (2675 3400);
DISPLAY 0.893617 (2675 3400);
PAINT PURPLE (2675 3400);
FORCENOTE
BOM_COST=PROC_SIDEBAND
(2125 650) 0;
DISPLAY LEFT (2125 650);
DISPLAY 1.957447 (2125 650);
PAINT PURPLE (2125 650);
FORCENOTE
TP FAB1 POP RES R7P14 0418
(-75 725) 0;
DISPLAY LEFT (-75 725);
DISPLAY 1.021277 (-75 725);
PAINT RED (-75 725);
FORCENOTE
BUILT IN SELF TEST
(2675 3850) 0;
DISPLAY LEFT (2675 3850);
DISPLAY 0.914894 (2675 3850);
PAINT PURPLE (2675 3850);
FORCENOTE
INTERNAL
(1775 4050) 0;
DISPLAY LEFT (1775 4050);
DISPLAY 0.723404 (1775 4050);
PAINT PURPLE (1775 4050);
FORCENOTE
1
(2125 3800) 0;
DISPLAY LEFT (2125 3800);
DISPLAY 0.893617 (2125 3800);
PAINT PURPLE (2125 3800);
FORCENOTE
TP FAB1 CHANGE R6D14 TO PD 0107
(-2125 3500) 0;
DISPLAY LEFT (-2125 3500);
DISPLAY 1.021277 (-2125 3500);
PAINT RED (-2125 3500);
FORCENOTE
TP FAB1 POP RES R5D4 0111
(-2150 3900) 0;
DISPLAY LEFT (-2150 3900);
DISPLAY 1.021277 (-2150 3900);
PAINT RED (-2150 3900);
FORCENOTE
MCI_BIST_ENABLE
(1025 3800) 0;
DISPLAY LEFT (1025 3800);
DISPLAY 0.893617 (1025 3800);
PAINT PURPLE (1025 3800);
FORCENOTE
(DEFAULT)
(2350 3975) 0;
DISPLAY LEFT (2350 3975);
DISPLAY 0.723404 (2350 3975);
PAINT PURPLE (2350 3975);
FORCENOTE
0
(2450 1550) 0;
DISPLAY LEFT (2450 1550);
DISPLAY 1.106383 (2450 1550);
PAINT PURPLE (2450 1550);
FORCENOTE
1
(2400 2025) 0;
DISPLAY LEFT (2400 2025);
DISPLAY 0.914894 (2400 2025);
PAINT PURPLE (2400 2025);
FORCENOTE
TP FAB1 CHANGE R3D25 TO PD 0107
(-2100 925) 0;
DISPLAY LEFT (-2100 925);
DISPLAY 1.021277 (-2100 925);
PAINT RED (-2100 925);
FORCENOTE
PD
(1825 2475) 0;
DISPLAY LEFT (1825 2475);
DISPLAY 0.893617 (1825 2475);
PAINT PURPLE (1825 2475);
FORCENOTE
SOCKET IDENTIFIER
(2675 2525) 0;
DISPLAY LEFT (2675 2525);
DISPLAY 0.893617 (2675 2525);
PAINT PURPLE (2675 2525);
FORCENOTE
PU
(1825 3025) 0;
DISPLAY LEFT (1825 3025);
DISPLAY 0.893617 (1825 3025);
PAINT PURPLE (1825 3025);
FORCENOTE
1: DMI MODE
(2725 2700) 0;
DISPLAY LEFT (2725 2700);
DISPLAY 0.893617 (2725 2700);
PAINT PURPLE (2725 2700);
FORCENOTE
(FOLLOW PDG P202)
(2650 2825) 0;
DISPLAY LEFT (2650 2825);
DISPLAY 0.808511 (2650 2825);
PAINT PURPLE (2650 2825);
FORCENOTE
PD
(1825 1800) 0;
DISPLAY LEFT (1825 1800);
DISPLAY 0.893617 (1825 1800);
PAINT PURPLE (1825 1800);
FORCENOTE
PU
(1825 3800) 0;
DISPLAY LEFT (1825 3800);
DISPLAY 0.893617 (1825 3800);
PAINT PURPLE (1825 3800);
FORCENOTE
PD
(1825 3575) 0;
DISPLAY LEFT (1825 3575);
DISPLAY 0.893617 (1825 3575);
PAINT PURPLE (1825 3575);
FORCENOTE
MCI_SAFE_MODE_BOOT
(1025 3575) 0;
DISPLAY LEFT (1025 3575);
DISPLAY 0.893617 (1025 3575);
PAINT PURPLE (1025 3575);
FORCENOTE
DESCRIPTION
(3225 4050) 0;
DISPLAY LEFT (3225 4050);
DISPLAY 0.893617 (3225 4050);
PAINT PURPLE (3225 4050);
FORCENOTE
PU
(1825 1275) 0;
DISPLAY LEFT (1825 1275);
DISPLAY 0.893617 (1825 1275);
PAINT PURPLE (1825 1275);
FORCENOTE
0: BIST DISABLED
(2725 3750) 0;
DISPLAY LEFT (2725 3750);
DISPLAY 0.893617 (2725 3750);
PAINT PURPLE (2725 3750);
FORCENOTE
CPU0
(2100 4050) 0;
DISPLAY LEFT (2100 4050);
DISPLAY 0.723404 (2100 4050);
PAINT PURPLE (2100 4050);
FORCENOTE
PU
(1825 2025) 0;
DISPLAY LEFT (1825 2025);
DISPLAY 0.893617 (1825 2025);
PAINT PURPLE (1825 2025);
FORCENOTE
ROOM=PROC_SIDEBAND
(2100 775) 0;
DISPLAY LEFT (2100 775);
DISPLAY 1.957447 (2100 775);
PAINT PURPLE (2100 775);
FORCENOTE
CPU1
(2400 4050) 0;
DISPLAY LEFT (2400 4050);
DISPLAY 0.723404 (2400 4050);
PAINT PURPLE (2400 4050);
FORCENOTE
1: BIST ENABLED
(2725 3800) 0;
DISPLAY LEFT (2725 3800);
DISPLAY 0.893617 (2725 3800);
PAINT PURPLE (2725 3800);
FORCENOTE
1
(2125 3350) 0;
DISPLAY LEFT (2125 3350);
DISPLAY 1.106383 (2125 3350);
PAINT PURPLE (2125 3350);
FORCENOTE
1:CONITINUE TO BOOT WITHOUT CLK ALIGNING
(2600 2000) 0;
DISPLAY LEFT (2600 2000);
DISPLAY 1.021277 (2600 2000);
PAINT PURPLE (2600 2000);
FORCENOTE
STRAPS (CPU0) 
(-3400 4875) 0;
DISPLAY LEFT (-3400 4875);
DISPLAY 1.595745 (-3400 4875);
PAINT PURPLE (-3400 4875);
QUIT
